FILE_TYPE = MACRO_DRAWING;
SET COLOR_WIRE YELLOW;
SET COLOR_PROP MONO;
SET COLOR_DOT WHITE;
SET COLOR_ARC YELLOW;
SET COLOR_BODY GREEN;
SET COLOR_NOTE MONO;
SET PROP_DISPLAY VALUE;
SET PAGE_NUMBER P116;
FORCEADD OFFPAGE..1
(-7200 2900);
FORCEPROP 2 LAST $XR0 172 
J 0
(-7452 2900);
DISPLAY 0.638298 (-7452 2900);
PAINT MONO (-7452 2900);
FORCEPROP 2 LAST PATH I101
J 0
(-7150 2975);
DISPLAY 1.361702 (-7150 2975);
PAINT ORANGE (-7150 2975);
DISPLAY INVISIBLE (-7150 2975);
FORCEPROP 2 LAST CDS_LIB mstr_standard
J 0
(-7200 2900);
PAINT ORANGE (-7200 2900);
DISPLAY INVISIBLE (-7200 2900);
FORCEPROP 1 LAST OFFPAGE TRUE
J 0
(-6875 2775);
PAINT GREEN (-6875 2775);
DISPLAY INVISIBLE (-6875 2775);
FORCEPROP 1 LAST COMMENT_BODY TRUE
J 0
(-7075 2800);
DISPLAY 1.170213 (-7075 2800);
PAINT PEACH (-7075 2800);
DISPLAY INVISIBLE (-7075 2800);
FORCEADD OFFPAGE..1
(-7200 2700);
FORCEPROP 2 LAST $XR0 139 
J 0
(-7452 2700);
DISPLAY 0.638298 (-7452 2700);
PAINT MONO (-7452 2700);
FORCEPROP 2 LAST PATH I102
J 0
(-7150 2775);
DISPLAY 1.361702 (-7150 2775);
PAINT ORANGE (-7150 2775);
DISPLAY INVISIBLE (-7150 2775);
FORCEPROP 2 LAST CDS_LIB mstr_standard
J 0
(-7200 2700);
PAINT ORANGE (-7200 2700);
DISPLAY INVISIBLE (-7200 2700);
FORCEPROP 1 LAST OFFPAGE TRUE
J 0
(-6875 2575);
PAINT GREEN (-6875 2575);
DISPLAY INVISIBLE (-6875 2575);
FORCEPROP 1 LAST COMMENT_BODY TRUE
J 0
(-7075 2600);
DISPLAY 1.170213 (-7075 2600);
PAINT PEACH (-7075 2600);
DISPLAY INVISIBLE (-7075 2600);
FORCEADD OFFPAGE..1
(-7200 2750);
FORCEPROP 2 LAST $XR0 139 
J 0
(-7452 2750);
DISPLAY 0.638298 (-7452 2750);
PAINT MONO (-7452 2750);
FORCEPROP 2 LAST PATH I103
J 0
(-7150 2825);
DISPLAY 1.361702 (-7150 2825);
PAINT ORANGE (-7150 2825);
DISPLAY INVISIBLE (-7150 2825);
FORCEPROP 2 LAST CDS_LIB mstr_standard
J 0
(-7200 2750);
PAINT ORANGE (-7200 2750);
DISPLAY INVISIBLE (-7200 2750);
FORCEPROP 1 LAST OFFPAGE TRUE
J 0
(-6875 2625);
PAINT GREEN (-6875 2625);
DISPLAY INVISIBLE (-6875 2625);
FORCEPROP 1 LAST COMMENT_BODY TRUE
J 0
(-7075 2650);
DISPLAY 1.170213 (-7075 2650);
PAINT PEACH (-7075 2650);
DISPLAY INVISIBLE (-7075 2650);
FORCEADD OFFPAGE..1
(-7200 2850);
FORCEPROP 2 LAST $XR0 185 
J 0
(-7452 2850);
DISPLAY 0.638298 (-7452 2850);
PAINT MONO (-7452 2850);
FORCEPROP 2 LAST PATH I104
J 0
(-7150 2925);
DISPLAY 1.361702 (-7150 2925);
PAINT ORANGE (-7150 2925);
DISPLAY INVISIBLE (-7150 2925);
FORCEPROP 2 LAST CDS_LIB mstr_standard
J 0
(-7200 2850);
PAINT ORANGE (-7200 2850);
DISPLAY INVISIBLE (-7200 2850);
FORCEPROP 1 LAST OFFPAGE TRUE
J 0
(-6875 2725);
PAINT GREEN (-6875 2725);
DISPLAY INVISIBLE (-6875 2725);
FORCEPROP 1 LAST COMMENT_BODY TRUE
J 0
(-7075 2750);
DISPLAY 1.170213 (-7075 2750);
PAINT PEACH (-7075 2750);
DISPLAY INVISIBLE (-7075 2750);
FORCEADD OFFPAGE..1
(-7200 2800);
FORCEPROP 2 LAST $XR0 185 
J 0
(-7452 2800);
DISPLAY 0.638298 (-7452 2800);
PAINT MONO (-7452 2800);
FORCEPROP 2 LAST PATH I105
J 0
(-7150 2875);
DISPLAY 1.361702 (-7150 2875);
PAINT ORANGE (-7150 2875);
DISPLAY INVISIBLE (-7150 2875);
FORCEPROP 2 LAST CDS_LIB mstr_standard
J 0
(-7200 2800);
PAINT ORANGE (-7200 2800);
DISPLAY INVISIBLE (-7200 2800);
FORCEPROP 1 LAST OFFPAGE TRUE
J 0
(-6875 2675);
PAINT GREEN (-6875 2675);
DISPLAY INVISIBLE (-6875 2675);
FORCEPROP 1 LAST COMMENT_BODY TRUE
J 0
(-7075 2700);
DISPLAY 1.170213 (-7075 2700);
PAINT PEACH (-7075 2700);
DISPLAY INVISIBLE (-7075 2700);
FORCEADD OFFPAGE..1
(-7200 2650);
FORCEPROP 2 LAST $XR1 116 
J 0
(-7572 2650);
DISPLAY 0.638298 (-7572 2650);
PAINT MONO (-7572 2650);
FORCEPROP 2 LAST $XR0 145 
J 0
(-7452 2650);
DISPLAY 0.638298 (-7452 2650);
PAINT MONO (-7452 2650);
FORCEPROP 2 LAST PATH I106
J 0
(-7150 2725);
DISPLAY 1.361702 (-7150 2725);
PAINT ORANGE (-7150 2725);
DISPLAY INVISIBLE (-7150 2725);
FORCEPROP 2 LAST CDS_LIB mstr_standard
J 0
(-7200 2650);
PAINT ORANGE (-7200 2650);
DISPLAY INVISIBLE (-7200 2650);
FORCEPROP 1 LAST OFFPAGE TRUE
J 0
(-6875 2525);
PAINT GREEN (-6875 2525);
DISPLAY INVISIBLE (-6875 2525);
FORCEPROP 1 LAST COMMENT_BODY TRUE
J 0
(-7075 2550);
DISPLAY 1.170213 (-7075 2550);
PAINT PEACH (-7075 2550);
DISPLAY INVISIBLE (-7075 2550);
FORCEADD OFFPAGE..1
(-7200 2600);
FORCEPROP 2 LAST $XR1 116 
J 0
(-7572 2600);
DISPLAY 0.638298 (-7572 2600);
PAINT MONO (-7572 2600);
FORCEPROP 2 LAST $XR0 145 
J 0
(-7452 2600);
DISPLAY 0.638298 (-7452 2600);
PAINT MONO (-7452 2600);
FORCEPROP 2 LAST PATH I107
J 0
(-7150 2675);
DISPLAY 1.361702 (-7150 2675);
PAINT ORANGE (-7150 2675);
DISPLAY INVISIBLE (-7150 2675);
FORCEPROP 2 LAST CDS_LIB mstr_standard
J 0
(-7200 2600);
PAINT ORANGE (-7200 2600);
DISPLAY INVISIBLE (-7200 2600);
FORCEPROP 1 LAST OFFPAGE TRUE
J 0
(-6875 2475);
PAINT GREEN (-6875 2475);
DISPLAY INVISIBLE (-6875 2475);
FORCEPROP 1 LAST COMMENT_BODY TRUE
J 0
(-7075 2500);
DISPLAY 1.170213 (-7075 2500);
PAINT PEACH (-7075 2500);
DISPLAY INVISIBLE (-7075 2500);
FORCEADD RES..2
R 2
(-7550 2150);
FORCEPROP 1 LASTPIN (-7550 2050) $PN 2
J 2
(-7555 2060);
DISPLAY 0.617021 (-7555 2060);
PAINT WHITE (-7555 2060);
FORCEPROP 1 LASTPIN (-7550 2250) $PN 1
J 2
(-7555 2212);
DISPLAY 0.617021 (-7555 2212);
PAINT WHITE (-7555 2212);
FORCEPROP 1 LAST TOLERANCE 1%
J 2
(-7595 2175);
DISPLAY 0.617021 (-7595 2175);
PAINT SKYBLUE (-7595 2175);
FORCEPROP 1 LAST WATTAGE 1/16W
J 2
(-7590 2125);
DISPLAY 0.617021 (-7590 2125);
PAINT SKYBLUE (-7590 2125);
FORCEPROP 1 LAST MATERIAL CHIP
J 2
(-7590 2075);
DISPLAY 0.617021 (-7590 2075);
PAINT SKYBLUE (-7590 2075);
FORCEPROP 1 LAST VALUE 100.0
J 2
(-7595 2225);
DISPLAY 0.617021 (-7595 2225);
PAINT SKYBLUE (-7595 2225);
FORCEPROP 1 LAST LOCATION R3M11
J 2
(-7595 2275);
DISPLAY 0.617021 (-7595 2275);
PAINT AQUA (-7595 2275);
FORCEPROP 1 LAST PART_NUMBER G21796-017
J 2
(-7590 2025);
DISPLAY 0.617021 (-7590 2025);
PAINT BLUE (-7590 2025);
FORCEPROP 1 LAST PACK_TYPE 0402
J 2
(-7590 1975);
DISPLAY 0.617021 (-7590 1975);
PAINT SKYBLUE (-7590 1975);
FORCEPROP 2 LAST SEC 1
J 0
(-7600 2375);
DISPLAY 0.680851 (-7600 2375);
PAINT MONO (-7600 2375);
DISPLAY INVISIBLE (-7600 2375);
FORCEPROP 2 LAST NO_XNET_CONNECTION 1
J 0
(-7600 2375);
PAINT MONO (-7600 2375);
DISPLAY INVISIBLE (-7600 2375);
FORCEPROP 0 LAST ROOM SB
J 2
(-7600 2375);
DISPLAY 1.021277 (-7600 2375);
PAINT ORANGE (-7600 2375);
DISPLAY INVISIBLE (-7600 2375);
FORCEPROP 2 LAST SEC_TYPE 0402
J 0
(-7600 2375);
DISPLAY 1.021277 (-7600 2375);
PAINT ORANGE (-7600 2375);
DISPLAY INVISIBLE (-7600 2375);
FORCEPROP 1 LAST PATH I108
J 2
(-7600 2325);
DISPLAY 0.978723 (-7600 2325);
PAINT WHITE (-7600 2325);
DISPLAY INVISIBLE (-7600 2325);
FORCEPROP 2 LAST CDS_LIB mstr_discrete
J 0
(-7550 2150);
PAINT ORANGE (-7550 2150);
DISPLAY INVISIBLE (-7550 2150);
FORCEPROP 2 LAST CDS_LOCATION R3M11
J 2
(-7595 2275);
DISPLAY 0.617021 (-7595 2275);
PAINT AQUA (-7595 2275);
DISPLAY INVISIBLE (-7595 2275);
FORCEADD TAP..1
(-1875 3900);
FORCEPROP 3 LASTPIN (-1925 3900) SIG_NAME SATA6G_PCH_PCIE_UP_SATA_TXN<5>
J 0
(-1915 3910);
DISPLAY 0.659574 (-1915 3910);
PAINT MONO (-1915 3910);
DISPLAY INVISIBLE (-1915 3910);
FORCEPROP 1 LASTPIN (-1925 3900) BN 5
J 0
(-1937 3908);
DISPLAY 0.617021 (-1937 3908);
PAINT GREEN (-1937 3908);
FORCEPROP 1 LAST PATH I122
J 0
(-1877 3900);
DISPLAY 0.872340 (-1877 3900);
PAINT GREEN (-1877 3900);
DISPLAY INVISIBLE (-1877 3900);
FORCEPROP 2 LAST CDS_LIB mstr_standard
J 0
(-1875 3900);
PAINT ORANGE (-1875 3900);
DISPLAY INVISIBLE (-1875 3900);
FORCEPROP 1 LAST BODY_TYPE PLUMBING
J 0
(-1875 3950);
DISPLAY 1.446809 (-1875 3950);
PAINT GREEN (-1875 3950);
DISPLAY INVISIBLE (-1875 3950);
FORCEPROP 1 LAST HDL_TAP TRUE
J 0
(-1550 3775);
DISPLAY 1.446809 (-1550 3775);
PAINT GREEN (-1550 3775);
DISPLAY INVISIBLE (-1550 3775);
FORCEADD TAP..1
(-1875 3800);
FORCEPROP 3 LASTPIN (-1925 3800) SIG_NAME SATA6G_PCH_PCIE_UP_SATA_TXN<4>
J 0
(-1915 3810);
DISPLAY 0.659574 (-1915 3810);
PAINT MONO (-1915 3810);
DISPLAY INVISIBLE (-1915 3810);
FORCEPROP 1 LASTPIN (-1925 3800) BN 4
J 0
(-1937 3808);
DISPLAY 0.617021 (-1937 3808);
PAINT GREEN (-1937 3808);
FORCEPROP 2 LAST CDS_LIB mstr_standard
J 0
(-1875 3800);
PAINT ORANGE (-1875 3800);
DISPLAY INVISIBLE (-1875 3800);
FORCEPROP 1 LAST PATH I123
J 0
(-1877 3800);
DISPLAY 0.872340 (-1877 3800);
PAINT GREEN (-1877 3800);
DISPLAY INVISIBLE (-1877 3800);
FORCEPROP 1 LAST BODY_TYPE PLUMBING
J 0
(-1875 3850);
DISPLAY 1.446809 (-1875 3850);
PAINT GREEN (-1875 3850);
DISPLAY INVISIBLE (-1875 3850);
FORCEPROP 1 LAST HDL_TAP TRUE
J 0
(-1550 3675);
DISPLAY 1.446809 (-1550 3675);
PAINT GREEN (-1550 3675);
DISPLAY INVISIBLE (-1550 3675);
FORCEADD TAP..1
(-2025 4150);
FORCEPROP 3 LASTPIN (-2075 4150) SIG_NAME SATA6G_PCH_PCIE_UP_SATA_TXP<7>
J 0
(-2065 4160);
DISPLAY 0.659574 (-2065 4160);
PAINT MONO (-2065 4160);
DISPLAY INVISIBLE (-2065 4160);
FORCEPROP 1 LASTPIN (-2075 4150) BN 7
J 0
(-2087 4158);
DISPLAY 0.617021 (-2087 4158);
PAINT GREEN (-2087 4158);
FORCEPROP 2 LAST CDS_LIB mstr_standard
J 0
(-2025 4150);
PAINT ORANGE (-2025 4150);
DISPLAY INVISIBLE (-2025 4150);
FORCEPROP 1 LAST PATH I125
J 0
(-2027 4150);
DISPLAY 0.872340 (-2027 4150);
PAINT GREEN (-2027 4150);
DISPLAY INVISIBLE (-2027 4150);
FORCEPROP 1 LAST BODY_TYPE PLUMBING
J 0
(-2025 4200);
DISPLAY 1.446809 (-2025 4200);
PAINT GREEN (-2025 4200);
DISPLAY INVISIBLE (-2025 4200);
FORCEPROP 1 LAST HDL_TAP TRUE
J 0
(-1700 4025);
DISPLAY 1.446809 (-1700 4025);
PAINT GREEN (-1700 4025);
DISPLAY INVISIBLE (-1700 4025);
FORCEADD TAP..1
(-2025 4050);
FORCEPROP 3 LASTPIN (-2075 4050) SIG_NAME SATA6G_PCH_PCIE_UP_SATA_TXP<6>
J 0
(-2065 4060);
DISPLAY 0.659574 (-2065 4060);
PAINT MONO (-2065 4060);
DISPLAY INVISIBLE (-2065 4060);
FORCEPROP 1 LASTPIN (-2075 4050) BN 6
J 0
(-2087 4058);
DISPLAY 0.617021 (-2087 4058);
PAINT GREEN (-2087 4058);
FORCEPROP 2 LAST CDS_LIB mstr_standard
J 0
(-2025 4050);
PAINT ORANGE (-2025 4050);
DISPLAY INVISIBLE (-2025 4050);
FORCEPROP 1 LAST PATH I128
J 0
(-2027 4050);
DISPLAY 0.872340 (-2027 4050);
PAINT GREEN (-2027 4050);
DISPLAY INVISIBLE (-2027 4050);
FORCEPROP 1 LAST BODY_TYPE PLUMBING
J 0
(-2025 4100);
DISPLAY 1.446809 (-2025 4100);
PAINT GREEN (-2025 4100);
DISPLAY INVISIBLE (-2025 4100);
FORCEPROP 1 LAST HDL_TAP TRUE
J 0
(-1700 3925);
DISPLAY 1.446809 (-1700 3925);
PAINT GREEN (-1700 3925);
DISPLAY INVISIBLE (-1700 3925);
FORCEADD TAP..1
(-1875 4000);
FORCEPROP 3 LASTPIN (-1925 4000) SIG_NAME SATA6G_PCH_PCIE_UP_SATA_TXN<6>
J 0
(-1915 4010);
DISPLAY 0.659574 (-1915 4010);
PAINT MONO (-1915 4010);
DISPLAY INVISIBLE (-1915 4010);
FORCEPROP 1 LASTPIN (-1925 4000) BN 6
J 0
(-1937 4008);
DISPLAY 0.617021 (-1937 4008);
PAINT GREEN (-1937 4008);
FORCEPROP 1 LAST PATH I129
J 0
(-1877 4000);
DISPLAY 0.872340 (-1877 4000);
PAINT GREEN (-1877 4000);
DISPLAY INVISIBLE (-1877 4000);
FORCEPROP 2 LAST CDS_LIB mstr_standard
J 0
(-1875 4000);
PAINT ORANGE (-1875 4000);
DISPLAY INVISIBLE (-1875 4000);
FORCEPROP 1 LAST BODY_TYPE PLUMBING
J 0
(-1875 4050);
DISPLAY 1.446809 (-1875 4050);
PAINT GREEN (-1875 4050);
DISPLAY INVISIBLE (-1875 4050);
FORCEPROP 1 LAST HDL_TAP TRUE
J 0
(-1550 3875);
DISPLAY 1.446809 (-1550 3875);
PAINT GREEN (-1550 3875);
DISPLAY INVISIBLE (-1550 3875);
FORCEADD TAP..1
(-1875 4100);
FORCEPROP 3 LASTPIN (-1925 4100) SIG_NAME SATA6G_PCH_PCIE_UP_SATA_TXN<7>
J 0
(-1915 4110);
DISPLAY 0.659574 (-1915 4110);
PAINT MONO (-1915 4110);
DISPLAY INVISIBLE (-1915 4110);
FORCEPROP 1 LASTPIN (-1925 4100) BN 7
J 0
(-1937 4108);
DISPLAY 0.617021 (-1937 4108);
PAINT GREEN (-1937 4108);
FORCEPROP 2 LAST CDS_LIB mstr_standard
J 0
(-1875 4100);
PAINT ORANGE (-1875 4100);
DISPLAY INVISIBLE (-1875 4100);
FORCEPROP 1 LAST PATH I130
J 0
(-1877 4100);
DISPLAY 0.872340 (-1877 4100);
PAINT GREEN (-1877 4100);
DISPLAY INVISIBLE (-1877 4100);
FORCEPROP 1 LAST BODY_TYPE PLUMBING
J 0
(-1875 4150);
DISPLAY 1.446809 (-1875 4150);
PAINT GREEN (-1875 4150);
DISPLAY INVISIBLE (-1875 4150);
FORCEPROP 1 LAST HDL_TAP TRUE
J 0
(-1550 3975);
DISPLAY 1.446809 (-1550 3975);
PAINT GREEN (-1550 3975);
DISPLAY INVISIBLE (-1550 3975);
FORCEADD TAP..1
(-1875 3700);
FORCEPROP 3 LASTPIN (-1925 3700) SIG_NAME SATA6G_PCH_PCIE_UP_SATA_TXN<3>
J 0
(-1915 3710);
DISPLAY 0.659574 (-1915 3710);
PAINT MONO (-1915 3710);
DISPLAY INVISIBLE (-1915 3710);
FORCEPROP 1 LASTPIN (-1925 3700) BN 3
J 0
(-1937 3708);
DISPLAY 0.617021 (-1937 3708);
PAINT GREEN (-1937 3708);
FORCEPROP 2 LAST CDS_LIB mstr_standard
J 0
(-1875 3700);
PAINT ORANGE (-1875 3700);
DISPLAY INVISIBLE (-1875 3700);
FORCEPROP 1 LAST PATH I131
J 0
(-1877 3700);
DISPLAY 0.872340 (-1877 3700);
PAINT GREEN (-1877 3700);
DISPLAY INVISIBLE (-1877 3700);
FORCEPROP 1 LAST BODY_TYPE PLUMBING
J 0
(-1875 3750);
DISPLAY 1.446809 (-1875 3750);
PAINT GREEN (-1875 3750);
DISPLAY INVISIBLE (-1875 3750);
FORCEPROP 1 LAST HDL_TAP TRUE
J 0
(-1550 3575);
DISPLAY 1.446809 (-1550 3575);
PAINT GREEN (-1550 3575);
DISPLAY INVISIBLE (-1550 3575);
FORCEADD TAP..1
(-1875 3600);
FORCEPROP 3 LASTPIN (-1925 3600) SIG_NAME SATA6G_PCH_PCIE_UP_SATA_TXN<2>
J 0
(-1915 3610);
DISPLAY 0.659574 (-1915 3610);
PAINT MONO (-1915 3610);
DISPLAY INVISIBLE (-1915 3610);
FORCEPROP 1 LASTPIN (-1925 3600) BN 2
J 0
(-1937 3608);
DISPLAY 0.617021 (-1937 3608);
PAINT GREEN (-1937 3608);
FORCEPROP 1 LAST PATH I132
J 0
(-1877 3600);
DISPLAY 0.872340 (-1877 3600);
PAINT GREEN (-1877 3600);
DISPLAY INVISIBLE (-1877 3600);
FORCEPROP 2 LAST CDS_LIB mstr_standard
J 0
(-1875 3600);
PAINT ORANGE (-1875 3600);
DISPLAY INVISIBLE (-1875 3600);
FORCEPROP 1 LAST BODY_TYPE PLUMBING
J 0
(-1875 3650);
DISPLAY 1.446809 (-1875 3650);
PAINT GREEN (-1875 3650);
DISPLAY INVISIBLE (-1875 3650);
FORCEPROP 1 LAST HDL_TAP TRUE
J 0
(-1550 3475);
DISPLAY 1.446809 (-1550 3475);
PAINT GREEN (-1550 3475);
DISPLAY INVISIBLE (-1550 3475);
FORCEADD TAP..1
(-1875 3500);
FORCEPROP 3 LASTPIN (-1925 3500) SIG_NAME SATA6G_PCH_PCIE_UP_SATA_TXN<1>
J 0
(-1915 3510);
DISPLAY 0.659574 (-1915 3510);
PAINT MONO (-1915 3510);
DISPLAY INVISIBLE (-1915 3510);
FORCEPROP 1 LASTPIN (-1925 3500) BN 1
J 0
(-1937 3508);
DISPLAY 0.617021 (-1937 3508);
PAINT GREEN (-1937 3508);
FORCEPROP 1 LAST PATH I133
J 0
(-1877 3500);
DISPLAY 0.872340 (-1877 3500);
PAINT GREEN (-1877 3500);
DISPLAY INVISIBLE (-1877 3500);
FORCEPROP 2 LAST CDS_LIB mstr_standard
J 0
(-1875 3500);
PAINT ORANGE (-1875 3500);
DISPLAY INVISIBLE (-1875 3500);
FORCEPROP 1 LAST BODY_TYPE PLUMBING
J 0
(-1875 3550);
DISPLAY 1.446809 (-1875 3550);
PAINT GREEN (-1875 3550);
DISPLAY INVISIBLE (-1875 3550);
FORCEPROP 1 LAST HDL_TAP TRUE
J 0
(-1550 3375);
DISPLAY 1.446809 (-1550 3375);
PAINT GREEN (-1550 3375);
DISPLAY INVISIBLE (-1550 3375);
FORCEADD TAP..1
(-1875 3400);
FORCEPROP 3 LASTPIN (-1925 3400) SIG_NAME SATA6G_PCH_PCIE_UP_SATA_TXN<0>
J 0
(-1915 3410);
DISPLAY 0.659574 (-1915 3410);
PAINT MONO (-1915 3410);
DISPLAY INVISIBLE (-1915 3410);
FORCEPROP 1 LASTPIN (-1925 3400) BN 0
J 0
(-1937 3408);
DISPLAY 0.617021 (-1937 3408);
PAINT GREEN (-1937 3408);
FORCEPROP 1 LAST PATH I134
J 0
(-1877 3400);
DISPLAY 0.872340 (-1877 3400);
PAINT GREEN (-1877 3400);
DISPLAY INVISIBLE (-1877 3400);
FORCEPROP 2 LAST CDS_LIB mstr_standard
J 0
(-1875 3400);
PAINT ORANGE (-1875 3400);
DISPLAY INVISIBLE (-1875 3400);
FORCEPROP 1 LAST BODY_TYPE PLUMBING
J 0
(-1875 3450);
DISPLAY 1.446809 (-1875 3450);
PAINT GREEN (-1875 3450);
DISPLAY INVISIBLE (-1875 3450);
FORCEPROP 1 LAST HDL_TAP TRUE
J 0
(-1550 3275);
DISPLAY 1.446809 (-1550 3275);
PAINT GREEN (-1550 3275);
DISPLAY INVISIBLE (-1550 3275);
FORCEADD TAP..1
(-2025 3950);
FORCEPROP 3 LASTPIN (-2075 3950) SIG_NAME SATA6G_PCH_PCIE_UP_SATA_TXP<5>
J 0
(-2065 3960);
DISPLAY 0.659574 (-2065 3960);
PAINT MONO (-2065 3960);
DISPLAY INVISIBLE (-2065 3960);
FORCEPROP 1 LASTPIN (-2075 3950) BN 5
J 0
(-2087 3958);
DISPLAY 0.617021 (-2087 3958);
PAINT GREEN (-2087 3958);
FORCEPROP 2 LAST CDS_LIB mstr_standard
J 0
(-2025 3950);
PAINT ORANGE (-2025 3950);
DISPLAY INVISIBLE (-2025 3950);
FORCEPROP 1 LAST PATH I135
J 0
(-2027 3950);
DISPLAY 0.872340 (-2027 3950);
PAINT GREEN (-2027 3950);
DISPLAY INVISIBLE (-2027 3950);
FORCEPROP 1 LAST BODY_TYPE PLUMBING
J 0
(-2025 4000);
DISPLAY 1.446809 (-2025 4000);
PAINT GREEN (-2025 4000);
DISPLAY INVISIBLE (-2025 4000);
FORCEPROP 1 LAST HDL_TAP TRUE
J 0
(-1700 3825);
DISPLAY 1.446809 (-1700 3825);
PAINT GREEN (-1700 3825);
DISPLAY INVISIBLE (-1700 3825);
FORCEADD TAP..1
(-2025 3850);
FORCEPROP 3 LASTPIN (-2075 3850) SIG_NAME SATA6G_PCH_PCIE_UP_SATA_TXP<4>
J 0
(-2065 3860);
DISPLAY 0.659574 (-2065 3860);
PAINT MONO (-2065 3860);
DISPLAY INVISIBLE (-2065 3860);
FORCEPROP 1 LASTPIN (-2075 3850) BN 4
J 0
(-2087 3858);
DISPLAY 0.617021 (-2087 3858);
PAINT GREEN (-2087 3858);
FORCEPROP 1 LAST PATH I136
J 0
(-2027 3850);
DISPLAY 0.872340 (-2027 3850);
PAINT GREEN (-2027 3850);
DISPLAY INVISIBLE (-2027 3850);
FORCEPROP 2 LAST CDS_LIB mstr_standard
J 0
(-2025 3850);
PAINT ORANGE (-2025 3850);
DISPLAY INVISIBLE (-2025 3850);
FORCEPROP 1 LAST BODY_TYPE PLUMBING
J 0
(-2025 3900);
DISPLAY 1.446809 (-2025 3900);
PAINT GREEN (-2025 3900);
DISPLAY INVISIBLE (-2025 3900);
FORCEPROP 1 LAST HDL_TAP TRUE
J 0
(-1700 3725);
DISPLAY 1.446809 (-1700 3725);
PAINT GREEN (-1700 3725);
DISPLAY INVISIBLE (-1700 3725);
FORCEADD TAP..1
(-2025 3750);
FORCEPROP 3 LASTPIN (-2075 3750) SIG_NAME SATA6G_PCH_PCIE_UP_SATA_TXP<3>
J 0
(-2065 3760);
DISPLAY 0.659574 (-2065 3760);
PAINT MONO (-2065 3760);
DISPLAY INVISIBLE (-2065 3760);
FORCEPROP 1 LASTPIN (-2075 3750) BN 3
J 0
(-2087 3758);
DISPLAY 0.617021 (-2087 3758);
PAINT GREEN (-2087 3758);
FORCEPROP 1 LAST PATH I137
J 0
(-2027 3750);
DISPLAY 0.872340 (-2027 3750);
PAINT GREEN (-2027 3750);
DISPLAY INVISIBLE (-2027 3750);
FORCEPROP 2 LAST CDS_LIB mstr_standard
J 0
(-2025 3750);
PAINT ORANGE (-2025 3750);
DISPLAY INVISIBLE (-2025 3750);
FORCEPROP 1 LAST BODY_TYPE PLUMBING
J 0
(-2025 3800);
DISPLAY 1.446809 (-2025 3800);
PAINT GREEN (-2025 3800);
DISPLAY INVISIBLE (-2025 3800);
FORCEPROP 1 LAST HDL_TAP TRUE
J 0
(-1700 3625);
DISPLAY 1.446809 (-1700 3625);
PAINT GREEN (-1700 3625);
DISPLAY INVISIBLE (-1700 3625);
FORCEADD TAP..1
(-2025 3650);
FORCEPROP 3 LASTPIN (-2075 3650) SIG_NAME SATA6G_PCH_PCIE_UP_SATA_TXP<2>
J 0
(-2065 3660);
DISPLAY 0.659574 (-2065 3660);
PAINT MONO (-2065 3660);
DISPLAY INVISIBLE (-2065 3660);
FORCEPROP 1 LASTPIN (-2075 3650) BN 2
J 0
(-2087 3658);
DISPLAY 0.617021 (-2087 3658);
PAINT GREEN (-2087 3658);
FORCEPROP 1 LAST PATH I138
J 0
(-2027 3650);
DISPLAY 0.872340 (-2027 3650);
PAINT GREEN (-2027 3650);
DISPLAY INVISIBLE (-2027 3650);
FORCEPROP 2 LAST CDS_LIB mstr_standard
J 0
(-2025 3650);
PAINT ORANGE (-2025 3650);
DISPLAY INVISIBLE (-2025 3650);
FORCEPROP 1 LAST BODY_TYPE PLUMBING
J 0
(-2025 3700);
DISPLAY 1.446809 (-2025 3700);
PAINT GREEN (-2025 3700);
DISPLAY INVISIBLE (-2025 3700);
FORCEPROP 1 LAST HDL_TAP TRUE
J 0
(-1700 3525);
DISPLAY 1.446809 (-1700 3525);
PAINT GREEN (-1700 3525);
DISPLAY INVISIBLE (-1700 3525);
FORCEADD TAP..1
(-2025 3550);
FORCEPROP 3 LASTPIN (-2075 3550) SIG_NAME SATA6G_PCH_PCIE_UP_SATA_TXP<1>
J 0
(-2065 3560);
DISPLAY 0.659574 (-2065 3560);
PAINT MONO (-2065 3560);
DISPLAY INVISIBLE (-2065 3560);
FORCEPROP 1 LASTPIN (-2075 3550) BN 1
J 0
(-2087 3558);
DISPLAY 0.617021 (-2087 3558);
PAINT GREEN (-2087 3558);
FORCEPROP 2 LAST CDS_LIB mstr_standard
J 0
(-2025 3550);
PAINT ORANGE (-2025 3550);
DISPLAY INVISIBLE (-2025 3550);
FORCEPROP 1 LAST PATH I139
J 0
(-2027 3550);
DISPLAY 0.872340 (-2027 3550);
PAINT GREEN (-2027 3550);
DISPLAY INVISIBLE (-2027 3550);
FORCEPROP 1 LAST BODY_TYPE PLUMBING
J 0
(-2025 3600);
DISPLAY 1.446809 (-2025 3600);
PAINT GREEN (-2025 3600);
DISPLAY INVISIBLE (-2025 3600);
FORCEPROP 1 LAST HDL_TAP TRUE
J 0
(-1700 3425);
DISPLAY 1.446809 (-1700 3425);
PAINT GREEN (-1700 3425);
DISPLAY INVISIBLE (-1700 3425);
FORCEADD TAP..1
(-2025 3450);
FORCEPROP 3 LASTPIN (-2075 3450) SIG_NAME SATA6G_PCH_PCIE_UP_SATA_TXP<0>
J 0
(-2065 3460);
DISPLAY 0.659574 (-2065 3460);
PAINT MONO (-2065 3460);
DISPLAY INVISIBLE (-2065 3460);
FORCEPROP 1 LASTPIN (-2075 3450) BN 0
J 0
(-2087 3458);
DISPLAY 0.617021 (-2087 3458);
PAINT GREEN (-2087 3458);
FORCEPROP 1 LAST PATH I140
J 0
(-2027 3450);
DISPLAY 0.872340 (-2027 3450);
PAINT GREEN (-2027 3450);
DISPLAY INVISIBLE (-2027 3450);
FORCEPROP 2 LAST CDS_LIB mstr_standard
J 0
(-2025 3450);
PAINT ORANGE (-2025 3450);
DISPLAY INVISIBLE (-2025 3450);
FORCEPROP 1 LAST BODY_TYPE PLUMBING
J 0
(-2025 3500);
DISPLAY 1.446809 (-2025 3500);
PAINT GREEN (-2025 3500);
DISPLAY INVISIBLE (-2025 3500);
FORCEPROP 1 LAST HDL_TAP TRUE
J 0
(-1700 3325);
DISPLAY 1.446809 (-1700 3325);
PAINT GREEN (-1700 3325);
DISPLAY INVISIBLE (-1700 3325);
FORCEADD TAP..1
R 2
(-6400 3450);
FORCEPROP 3 LASTPIN (-6350 3450) SIG_NAME SATA6G_PCH_PCIE_UP_SATA_RXP<0>
J 0
(-6340 3460);
DISPLAY 0.659574 (-6340 3460);
PAINT MONO (-6340 3460);
DISPLAY INVISIBLE (-6340 3460);
FORCEPROP 1 LASTPIN (-6350 3450) BN 0
J 2
(-6338 3458);
DISPLAY 0.617021 (-6338 3458);
PAINT GREEN (-6338 3458);
FORCEPROP 1 LAST PATH I141
J 2
(-6398 3450);
DISPLAY 0.872340 (-6398 3450);
PAINT GREEN (-6398 3450);
DISPLAY INVISIBLE (-6398 3450);
FORCEPROP 2 LAST CDS_LIB mstr_standard
J 2
(-6400 3450);
PAINT ORANGE (-6400 3450);
DISPLAY INVISIBLE (-6400 3450);
FORCEPROP 1 LAST BODY_TYPE PLUMBING
J 2
(-6400 3500);
DISPLAY 1.446809 (-6400 3500);
PAINT GREEN (-6400 3500);
DISPLAY INVISIBLE (-6400 3500);
FORCEPROP 1 LAST HDL_TAP TRUE
J 2
(-6725 3325);
DISPLAY 1.446809 (-6725 3325);
PAINT GREEN (-6725 3325);
DISPLAY INVISIBLE (-6725 3325);
FORCEADD TAP..1
R 2
(-6250 3400);
FORCEPROP 3 LASTPIN (-6200 3400) SIG_NAME SATA6G_PCH_PCIE_UP_SATA_RXN<0>
J 0
(-6190 3410);
DISPLAY 0.659574 (-6190 3410);
PAINT MONO (-6190 3410);
DISPLAY INVISIBLE (-6190 3410);
FORCEPROP 1 LASTPIN (-6200 3400) BN 0
J 2
(-6188 3408);
DISPLAY 0.617021 (-6188 3408);
PAINT GREEN (-6188 3408);
FORCEPROP 1 LAST PATH I142
J 2
(-6248 3400);
DISPLAY 0.872340 (-6248 3400);
PAINT GREEN (-6248 3400);
DISPLAY INVISIBLE (-6248 3400);
FORCEPROP 2 LAST CDS_LIB mstr_standard
J 2
(-6250 3400);
PAINT ORANGE (-6250 3400);
DISPLAY INVISIBLE (-6250 3400);
FORCEPROP 1 LAST BODY_TYPE PLUMBING
J 2
(-6250 3450);
DISPLAY 1.446809 (-6250 3450);
PAINT GREEN (-6250 3450);
DISPLAY INVISIBLE (-6250 3450);
FORCEPROP 1 LAST HDL_TAP TRUE
J 2
(-6575 3275);
DISPLAY 1.446809 (-6575 3275);
PAINT GREEN (-6575 3275);
DISPLAY INVISIBLE (-6575 3275);
FORCEADD TAP..1
R 2
(-6250 3500);
FORCEPROP 3 LASTPIN (-6200 3500) SIG_NAME SATA6G_PCH_PCIE_UP_SATA_RXN<1>
J 0
(-6190 3510);
DISPLAY 0.659574 (-6190 3510);
PAINT MONO (-6190 3510);
DISPLAY INVISIBLE (-6190 3510);
FORCEPROP 1 LASTPIN (-6200 3500) BN 1
J 2
(-6188 3508);
DISPLAY 0.617021 (-6188 3508);
PAINT GREEN (-6188 3508);
FORCEPROP 2 LAST CDS_LIB mstr_standard
J 2
(-6250 3500);
PAINT ORANGE (-6250 3500);
DISPLAY INVISIBLE (-6250 3500);
FORCEPROP 1 LAST PATH I143
J 2
(-6248 3500);
DISPLAY 0.872340 (-6248 3500);
PAINT GREEN (-6248 3500);
DISPLAY INVISIBLE (-6248 3500);
FORCEPROP 1 LAST BODY_TYPE PLUMBING
J 2
(-6250 3550);
DISPLAY 1.446809 (-6250 3550);
PAINT GREEN (-6250 3550);
DISPLAY INVISIBLE (-6250 3550);
FORCEPROP 1 LAST HDL_TAP TRUE
J 2
(-6575 3375);
DISPLAY 1.446809 (-6575 3375);
PAINT GREEN (-6575 3375);
DISPLAY INVISIBLE (-6575 3375);
FORCEADD TAP..1
R 2
(-6400 3650);
FORCEPROP 3 LASTPIN (-6350 3650) SIG_NAME SATA6G_PCH_PCIE_UP_SATA_RXP<2>
J 0
(-6340 3660);
DISPLAY 0.659574 (-6340 3660);
PAINT MONO (-6340 3660);
DISPLAY INVISIBLE (-6340 3660);
FORCEPROP 1 LASTPIN (-6350 3650) BN 2
J 2
(-6338 3658);
DISPLAY 0.617021 (-6338 3658);
PAINT GREEN (-6338 3658);
FORCEPROP 1 LAST PATH I144
J 2
(-6398 3650);
DISPLAY 0.872340 (-6398 3650);
PAINT GREEN (-6398 3650);
DISPLAY INVISIBLE (-6398 3650);
FORCEPROP 2 LAST CDS_LIB mstr_standard
J 2
(-6400 3650);
PAINT ORANGE (-6400 3650);
DISPLAY INVISIBLE (-6400 3650);
FORCEPROP 1 LAST BODY_TYPE PLUMBING
J 2
(-6400 3700);
DISPLAY 1.446809 (-6400 3700);
PAINT GREEN (-6400 3700);
DISPLAY INVISIBLE (-6400 3700);
FORCEPROP 1 LAST HDL_TAP TRUE
J 2
(-6725 3525);
DISPLAY 1.446809 (-6725 3525);
PAINT GREEN (-6725 3525);
DISPLAY INVISIBLE (-6725 3525);
FORCEADD TAP..1
R 2
(-6400 3750);
FORCEPROP 3 LASTPIN (-6350 3750) SIG_NAME SATA6G_PCH_PCIE_UP_SATA_RXP<3>
J 0
(-6340 3760);
DISPLAY 0.659574 (-6340 3760);
PAINT MONO (-6340 3760);
DISPLAY INVISIBLE (-6340 3760);
FORCEPROP 1 LASTPIN (-6350 3750) BN 3
J 2
(-6338 3758);
DISPLAY 0.617021 (-6338 3758);
PAINT GREEN (-6338 3758);
FORCEPROP 1 LAST PATH I145
J 2
(-6398 3750);
DISPLAY 0.872340 (-6398 3750);
PAINT GREEN (-6398 3750);
DISPLAY INVISIBLE (-6398 3750);
FORCEPROP 2 LAST CDS_LIB mstr_standard
J 2
(-6400 3750);
PAINT ORANGE (-6400 3750);
DISPLAY INVISIBLE (-6400 3750);
FORCEPROP 1 LAST BODY_TYPE PLUMBING
J 2
(-6400 3800);
DISPLAY 1.446809 (-6400 3800);
PAINT GREEN (-6400 3800);
DISPLAY INVISIBLE (-6400 3800);
FORCEPROP 1 LAST HDL_TAP TRUE
J 2
(-6725 3625);
DISPLAY 1.446809 (-6725 3625);
PAINT GREEN (-6725 3625);
DISPLAY INVISIBLE (-6725 3625);
FORCEADD TAP..1
R 2
(-6400 3550);
FORCEPROP 3 LASTPIN (-6350 3550) SIG_NAME SATA6G_PCH_PCIE_UP_SATA_RXP<1>
J 0
(-6340 3560);
DISPLAY 0.659574 (-6340 3560);
PAINT MONO (-6340 3560);
DISPLAY INVISIBLE (-6340 3560);
FORCEPROP 1 LASTPIN (-6350 3550) BN 1
J 2
(-6338 3558);
DISPLAY 0.617021 (-6338 3558);
PAINT GREEN (-6338 3558);
FORCEPROP 2 LAST CDS_LIB mstr_standard
J 2
(-6400 3550);
PAINT ORANGE (-6400 3550);
DISPLAY INVISIBLE (-6400 3550);
FORCEPROP 1 LAST PATH I146
J 2
(-6398 3550);
DISPLAY 0.872340 (-6398 3550);
PAINT GREEN (-6398 3550);
DISPLAY INVISIBLE (-6398 3550);
FORCEPROP 1 LAST BODY_TYPE PLUMBING
J 2
(-6400 3600);
DISPLAY 1.446809 (-6400 3600);
PAINT GREEN (-6400 3600);
DISPLAY INVISIBLE (-6400 3600);
FORCEPROP 1 LAST HDL_TAP TRUE
J 2
(-6725 3425);
DISPLAY 1.446809 (-6725 3425);
PAINT GREEN (-6725 3425);
DISPLAY INVISIBLE (-6725 3425);
FORCEADD TAP..1
R 2
(-6250 3600);
FORCEPROP 3 LASTPIN (-6200 3600) SIG_NAME SATA6G_PCH_PCIE_UP_SATA_RXN<2>
J 0
(-6190 3610);
DISPLAY 0.659574 (-6190 3610);
PAINT MONO (-6190 3610);
DISPLAY INVISIBLE (-6190 3610);
FORCEPROP 1 LASTPIN (-6200 3600) BN 2
J 2
(-6188 3608);
DISPLAY 0.617021 (-6188 3608);
PAINT GREEN (-6188 3608);
FORCEPROP 2 LAST CDS_LIB mstr_standard
J 2
(-6250 3600);
PAINT ORANGE (-6250 3600);
DISPLAY INVISIBLE (-6250 3600);
FORCEPROP 1 LAST PATH I147
J 2
(-6248 3600);
DISPLAY 0.872340 (-6248 3600);
PAINT GREEN (-6248 3600);
DISPLAY INVISIBLE (-6248 3600);
FORCEPROP 1 LAST BODY_TYPE PLUMBING
J 2
(-6250 3650);
DISPLAY 1.446809 (-6250 3650);
PAINT GREEN (-6250 3650);
DISPLAY INVISIBLE (-6250 3650);
FORCEPROP 1 LAST HDL_TAP TRUE
J 2
(-6575 3475);
DISPLAY 1.446809 (-6575 3475);
PAINT GREEN (-6575 3475);
DISPLAY INVISIBLE (-6575 3475);
FORCEADD TAP..1
R 2
(-6250 3700);
FORCEPROP 3 LASTPIN (-6200 3700) SIG_NAME SATA6G_PCH_PCIE_UP_SATA_RXN<3>
J 0
(-6190 3710);
DISPLAY 0.659574 (-6190 3710);
PAINT MONO (-6190 3710);
DISPLAY INVISIBLE (-6190 3710);
FORCEPROP 1 LASTPIN (-6200 3700) BN 3
J 2
(-6188 3708);
DISPLAY 0.617021 (-6188 3708);
PAINT GREEN (-6188 3708);
FORCEPROP 1 LAST PATH I148
J 2
(-6248 3700);
DISPLAY 0.872340 (-6248 3700);
PAINT GREEN (-6248 3700);
DISPLAY INVISIBLE (-6248 3700);
FORCEPROP 2 LAST CDS_LIB mstr_standard
J 2
(-6250 3700);
PAINT ORANGE (-6250 3700);
DISPLAY INVISIBLE (-6250 3700);
FORCEPROP 1 LAST BODY_TYPE PLUMBING
J 2
(-6250 3750);
DISPLAY 1.446809 (-6250 3750);
PAINT GREEN (-6250 3750);
DISPLAY INVISIBLE (-6250 3750);
FORCEPROP 1 LAST HDL_TAP TRUE
J 2
(-6575 3575);
DISPLAY 1.446809 (-6575 3575);
PAINT GREEN (-6575 3575);
DISPLAY INVISIBLE (-6575 3575);
FORCEADD TAP..1
R 2
(-6400 3850);
FORCEPROP 3 LASTPIN (-6350 3850) SIG_NAME SATA6G_PCH_PCIE_UP_SATA_RXP<4>
J 0
(-6340 3860);
DISPLAY 0.659574 (-6340 3860);
PAINT MONO (-6340 3860);
DISPLAY INVISIBLE (-6340 3860);
FORCEPROP 1 LASTPIN (-6350 3850) BN 4
J 2
(-6338 3858);
DISPLAY 0.617021 (-6338 3858);
PAINT GREEN (-6338 3858);
FORCEPROP 1 LAST PATH I149
J 2
(-6398 3850);
DISPLAY 0.872340 (-6398 3850);
PAINT GREEN (-6398 3850);
DISPLAY INVISIBLE (-6398 3850);
FORCEPROP 2 LAST CDS_LIB mstr_standard
J 2
(-6400 3850);
PAINT ORANGE (-6400 3850);
DISPLAY INVISIBLE (-6400 3850);
FORCEPROP 1 LAST BODY_TYPE PLUMBING
J 2
(-6400 3900);
DISPLAY 1.446809 (-6400 3900);
PAINT GREEN (-6400 3900);
DISPLAY INVISIBLE (-6400 3900);
FORCEPROP 1 LAST HDL_TAP TRUE
J 2
(-6725 3725);
DISPLAY 1.446809 (-6725 3725);
PAINT GREEN (-6725 3725);
DISPLAY INVISIBLE (-6725 3725);
FORCEADD TAP..1
R 2
(-6400 3950);
FORCEPROP 3 LASTPIN (-6350 3950) SIG_NAME SATA6G_PCH_PCIE_UP_SATA_RXP<5>
J 0
(-6340 3960);
DISPLAY 0.659574 (-6340 3960);
PAINT MONO (-6340 3960);
DISPLAY INVISIBLE (-6340 3960);
FORCEPROP 1 LASTPIN (-6350 3950) BN 5
J 2
(-6338 3958);
DISPLAY 0.617021 (-6338 3958);
PAINT GREEN (-6338 3958);
FORCEPROP 1 LAST PATH I150
J 2
(-6398 3950);
DISPLAY 0.872340 (-6398 3950);
PAINT GREEN (-6398 3950);
DISPLAY INVISIBLE (-6398 3950);
FORCEPROP 2 LAST CDS_LIB mstr_standard
J 2
(-6400 3950);
PAINT ORANGE (-6400 3950);
DISPLAY INVISIBLE (-6400 3950);
FORCEPROP 1 LAST BODY_TYPE PLUMBING
J 2
(-6400 4000);
DISPLAY 1.446809 (-6400 4000);
PAINT GREEN (-6400 4000);
DISPLAY INVISIBLE (-6400 4000);
FORCEPROP 1 LAST HDL_TAP TRUE
J 2
(-6725 3825);
DISPLAY 1.446809 (-6725 3825);
PAINT GREEN (-6725 3825);
DISPLAY INVISIBLE (-6725 3825);
FORCEADD TAP..1
R 2
(-6250 4000);
FORCEPROP 3 LASTPIN (-6200 4000) SIG_NAME SATA6G_PCH_PCIE_UP_SATA_RXN<6>
J 0
(-6190 4010);
DISPLAY 0.659574 (-6190 4010);
PAINT MONO (-6190 4010);
DISPLAY INVISIBLE (-6190 4010);
FORCEPROP 1 LASTPIN (-6200 4000) BN 6
J 2
(-6188 4008);
DISPLAY 0.617021 (-6188 4008);
PAINT GREEN (-6188 4008);
FORCEPROP 1 LAST PATH I151
J 2
(-6248 4000);
DISPLAY 0.872340 (-6248 4000);
PAINT GREEN (-6248 4000);
DISPLAY INVISIBLE (-6248 4000);
FORCEPROP 2 LAST CDS_LIB mstr_standard
J 2
(-6250 4000);
PAINT ORANGE (-6250 4000);
DISPLAY INVISIBLE (-6250 4000);
FORCEPROP 1 LAST BODY_TYPE PLUMBING
J 2
(-6250 4050);
DISPLAY 1.446809 (-6250 4050);
PAINT GREEN (-6250 4050);
DISPLAY INVISIBLE (-6250 4050);
FORCEPROP 1 LAST HDL_TAP TRUE
J 2
(-6575 3875);
DISPLAY 1.446809 (-6575 3875);
PAINT GREEN (-6575 3875);
DISPLAY INVISIBLE (-6575 3875);
FORCEADD TAP..1
R 2
(-6250 3900);
FORCEPROP 3 LASTPIN (-6200 3900) SIG_NAME SATA6G_PCH_PCIE_UP_SATA_RXN<5>
J 0
(-6190 3910);
DISPLAY 0.659574 (-6190 3910);
PAINT MONO (-6190 3910);
DISPLAY INVISIBLE (-6190 3910);
FORCEPROP 1 LASTPIN (-6200 3900) BN 5
J 2
(-6188 3908);
DISPLAY 0.617021 (-6188 3908);
PAINT GREEN (-6188 3908);
FORCEPROP 1 LAST PATH I152
J 2
(-6248 3900);
DISPLAY 0.872340 (-6248 3900);
PAINT GREEN (-6248 3900);
DISPLAY INVISIBLE (-6248 3900);
FORCEPROP 2 LAST CDS_LIB mstr_standard
J 2
(-6250 3900);
PAINT ORANGE (-6250 3900);
DISPLAY INVISIBLE (-6250 3900);
FORCEPROP 1 LAST BODY_TYPE PLUMBING
J 2
(-6250 3950);
DISPLAY 1.446809 (-6250 3950);
PAINT GREEN (-6250 3950);
DISPLAY INVISIBLE (-6250 3950);
FORCEPROP 1 LAST HDL_TAP TRUE
J 2
(-6575 3775);
DISPLAY 1.446809 (-6575 3775);
PAINT GREEN (-6575 3775);
DISPLAY INVISIBLE (-6575 3775);
FORCEADD TAP..1
R 2
(-6250 3800);
FORCEPROP 3 LASTPIN (-6200 3800) SIG_NAME SATA6G_PCH_PCIE_UP_SATA_RXN<4>
J 0
(-6190 3810);
DISPLAY 0.659574 (-6190 3810);
PAINT MONO (-6190 3810);
DISPLAY INVISIBLE (-6190 3810);
FORCEPROP 1 LASTPIN (-6200 3800) BN 4
J 2
(-6188 3808);
DISPLAY 0.617021 (-6188 3808);
PAINT GREEN (-6188 3808);
FORCEPROP 2 LAST CDS_LIB mstr_standard
J 2
(-6250 3800);
PAINT ORANGE (-6250 3800);
DISPLAY INVISIBLE (-6250 3800);
FORCEPROP 1 LAST PATH I153
J 2
(-6248 3800);
DISPLAY 0.872340 (-6248 3800);
PAINT GREEN (-6248 3800);
DISPLAY INVISIBLE (-6248 3800);
FORCEPROP 1 LAST BODY_TYPE PLUMBING
J 2
(-6250 3850);
DISPLAY 1.446809 (-6250 3850);
PAINT GREEN (-6250 3850);
DISPLAY INVISIBLE (-6250 3850);
FORCEPROP 1 LAST HDL_TAP TRUE
J 2
(-6575 3675);
DISPLAY 1.446809 (-6575 3675);
PAINT GREEN (-6575 3675);
DISPLAY INVISIBLE (-6575 3675);
FORCEADD TAP..1
R 2
(-6400 4150);
FORCEPROP 3 LASTPIN (-6350 4150) SIG_NAME SATA6G_PCH_PCIE_UP_SATA_RXP<7>
J 0
(-6340 4160);
DISPLAY 0.659574 (-6340 4160);
PAINT MONO (-6340 4160);
DISPLAY INVISIBLE (-6340 4160);
FORCEPROP 1 LASTPIN (-6350 4150) BN 7
J 2
(-6338 4158);
DISPLAY 0.617021 (-6338 4158);
PAINT GREEN (-6338 4158);
FORCEPROP 1 LAST PATH I154
J 2
(-6398 4150);
DISPLAY 0.872340 (-6398 4150);
PAINT GREEN (-6398 4150);
DISPLAY INVISIBLE (-6398 4150);
FORCEPROP 2 LAST CDS_LIB mstr_standard
J 2
(-6400 4150);
PAINT ORANGE (-6400 4150);
DISPLAY INVISIBLE (-6400 4150);
FORCEPROP 1 LAST BODY_TYPE PLUMBING
J 2
(-6400 4200);
DISPLAY 1.446809 (-6400 4200);
PAINT GREEN (-6400 4200);
DISPLAY INVISIBLE (-6400 4200);
FORCEPROP 1 LAST HDL_TAP TRUE
J 2
(-6725 4025);
DISPLAY 1.446809 (-6725 4025);
PAINT GREEN (-6725 4025);
DISPLAY INVISIBLE (-6725 4025);
FORCEADD TAP..1
R 2
(-6400 4050);
FORCEPROP 3 LASTPIN (-6350 4050) SIG_NAME SATA6G_PCH_PCIE_UP_SATA_RXP<6>
J 0
(-6340 4060);
DISPLAY 0.659574 (-6340 4060);
PAINT MONO (-6340 4060);
DISPLAY INVISIBLE (-6340 4060);
FORCEPROP 1 LASTPIN (-6350 4050) BN 6
J 2
(-6338 4058);
DISPLAY 0.617021 (-6338 4058);
PAINT GREEN (-6338 4058);
FORCEPROP 1 LAST PATH I155
J 2
(-6398 4050);
DISPLAY 0.872340 (-6398 4050);
PAINT GREEN (-6398 4050);
DISPLAY INVISIBLE (-6398 4050);
FORCEPROP 2 LAST CDS_LIB mstr_standard
J 2
(-6400 4050);
PAINT ORANGE (-6400 4050);
DISPLAY INVISIBLE (-6400 4050);
FORCEPROP 1 LAST BODY_TYPE PLUMBING
J 2
(-6400 4100);
DISPLAY 1.446809 (-6400 4100);
PAINT GREEN (-6400 4100);
DISPLAY INVISIBLE (-6400 4100);
FORCEPROP 1 LAST HDL_TAP TRUE
J 2
(-6725 3925);
DISPLAY 1.446809 (-6725 3925);
PAINT GREEN (-6725 3925);
DISPLAY INVISIBLE (-6725 3925);
FORCEADD TAP..1
R 2
(-6250 4100);
FORCEPROP 3 LASTPIN (-6200 4100) SIG_NAME SATA6G_PCH_PCIE_UP_SATA_RXN<7>
J 0
(-6190 4110);
DISPLAY 0.659574 (-6190 4110);
PAINT MONO (-6190 4110);
DISPLAY INVISIBLE (-6190 4110);
FORCEPROP 1 LASTPIN (-6200 4100) BN 7
J 2
(-6188 4108);
DISPLAY 0.617021 (-6188 4108);
PAINT GREEN (-6188 4108);
FORCEPROP 2 LAST CDS_LIB mstr_standard
J 2
(-6250 4100);
PAINT ORANGE (-6250 4100);
DISPLAY INVISIBLE (-6250 4100);
FORCEPROP 1 LAST PATH I156
J 2
(-6248 4100);
DISPLAY 0.872340 (-6248 4100);
PAINT GREEN (-6248 4100);
DISPLAY INVISIBLE (-6248 4100);
FORCEPROP 1 LAST BODY_TYPE PLUMBING
J 2
(-6250 4150);
DISPLAY 1.446809 (-6250 4150);
PAINT GREEN (-6250 4150);
DISPLAY INVISIBLE (-6250 4150);
FORCEPROP 1 LAST HDL_TAP TRUE
J 2
(-6575 3975);
DISPLAY 1.446809 (-6575 3975);
PAINT GREEN (-6575 3975);
DISPLAY INVISIBLE (-6575 3975);
FORCEADD RES..2
R 2
(-7125 2150);
FORCEPROP 1 LAST PACK_TYPE 0402
J 2
(-7165 1975);
DISPLAY 0.617021 (-7165 1975);
PAINT SKYBLUE (-7165 1975);
FORCEPROP 1 LAST WATTAGE 1/16W
J 2
(-7165 2125);
DISPLAY 0.617021 (-7165 2125);
PAINT SKYBLUE (-7165 2125);
FORCEPROP 1 LAST LOCATION R3M12
J 2
(-7170 2275);
DISPLAY 0.617021 (-7170 2275);
PAINT AQUA (-7170 2275);
FORCEPROP 1 LASTPIN (-7125 2250) $PN 1
J 2
(-7130 2212);
DISPLAY 0.617021 (-7130 2212);
PAINT ORANGE (-7130 2212);
FORCEPROP 1 LASTPIN (-7125 2050) $PN 2
J 2
(-7130 2060);
DISPLAY 0.617021 (-7130 2060);
PAINT ORANGE (-7130 2060);
FORCEPROP 1 LAST MATERIAL CHIP
J 2
(-7165 2075);
DISPLAY 0.617021 (-7165 2075);
PAINT SKYBLUE (-7165 2075);
FORCEPROP 1 LAST TOLERANCE 1%
J 2
(-7170 2175);
DISPLAY 0.617021 (-7170 2175);
PAINT SKYBLUE (-7170 2175);
FORCEPROP 1 LAST VALUE 100.0
J 2
(-7170 2225);
DISPLAY 0.617021 (-7170 2225);
PAINT SKYBLUE (-7170 2225);
FORCEPROP 1 LAST PART_NUMBER G21796-017
J 2
(-7165 2025);
DISPLAY 0.617021 (-7165 2025);
PAINT BLUE (-7165 2025);
FORCEPROP 2 LAST CDS_LIB mstr_discrete
J 0
(-7125 2150);
PAINT ORANGE (-7125 2150);
DISPLAY INVISIBLE (-7125 2150);
FORCEPROP 2 LAST SEC 1
J 0
(-7175 2375);
DISPLAY 0.680851 (-7175 2375);
PAINT MONO (-7175 2375);
DISPLAY INVISIBLE (-7175 2375);
FORCEPROP 2 LAST CDS_LOCATION R3M12
J 2
(-7170 2275);
DISPLAY 0.617021 (-7170 2275);
PAINT AQUA (-7170 2275);
DISPLAY INVISIBLE (-7170 2275);
FORCEPROP 2 LAST NO_XNET_CONNECTION 1
J 0
(-7175 2375);
PAINT MONO (-7175 2375);
DISPLAY INVISIBLE (-7175 2375);
FORCEPROP 0 LAST ROOM SB
J 2
(-7175 2375);
DISPLAY 1.021277 (-7175 2375);
PAINT ORANGE (-7175 2375);
DISPLAY INVISIBLE (-7175 2375);
FORCEPROP 2 LAST SEC_TYPE 0402
J 0
(-7175 2375);
DISPLAY 1.021277 (-7175 2375);
PAINT ORANGE (-7175 2375);
DISPLAY INVISIBLE (-7175 2375);
FORCEPROP 1 LAST PATH I181
J 2
(-7175 2325);
DISPLAY 0.978723 (-7175 2325);
PAINT WHITE (-7175 2325);
DISPLAY INVISIBLE (-7175 2325);
FORCEADD OFFPAGE..2
(-1750 2450);
FORCEPROP 2 LAST $XR0 185 
J 0
(-1561 2450);
DISPLAY 0.638298 (-1561 2450);
PAINT MONO (-1561 2450);
FORCEPROP 2 LAST PATH I204
J 0
(-1550 2500);
DISPLAY 1.021277 (-1550 2500);
PAINT ORANGE (-1550 2500);
DISPLAY INVISIBLE (-1550 2500);
FORCEPROP 2 LAST CDS_LIB mstr_standard
J 0
(-1750 2450);
PAINT ORANGE (-1750 2450);
DISPLAY INVISIBLE (-1750 2450);
FORCEPROP 1 LAST OFFPAGE TRUE
J 0
(-1425 2325);
PAINT GREEN (-1425 2325);
DISPLAY INVISIBLE (-1425 2325);
FORCEPROP 1 LAST COMMENT_BODY TRUE
J 0
(-1795 2355);
DISPLAY 1.170213 (-1795 2355);
PAINT PEACH (-1795 2355);
DISPLAY INVISIBLE (-1795 2355);
FORCEADD OFFPAGE..2
(-1750 2400);
FORCEPROP 2 LAST $XR0 185 
J 0
(-1561 2400);
DISPLAY 0.638298 (-1561 2400);
PAINT MONO (-1561 2400);
FORCEPROP 2 LAST PATH I205
J 0
(-1550 2450);
DISPLAY 1.021277 (-1550 2450);
PAINT ORANGE (-1550 2450);
DISPLAY INVISIBLE (-1550 2450);
FORCEPROP 2 LAST CDS_LIB mstr_standard
J 0
(-1750 2400);
PAINT ORANGE (-1750 2400);
DISPLAY INVISIBLE (-1750 2400);
FORCEPROP 1 LAST OFFPAGE TRUE
J 0
(-1425 2275);
PAINT GREEN (-1425 2275);
DISPLAY INVISIBLE (-1425 2275);
FORCEPROP 1 LAST COMMENT_BODY TRUE
J 0
(-1795 2305);
DISPLAY 1.170213 (-1795 2305);
PAINT PEACH (-1795 2305);
DISPLAY INVISIBLE (-1795 2305);
FORCEADD OFFPAGE..2
(-1750 2350);
FORCEPROP 2 LAST $XR0 185 
J 0
(-1561 2350);
DISPLAY 0.638298 (-1561 2350);
PAINT MONO (-1561 2350);
FORCEPROP 2 LAST PATH I206
J 0
(-1550 2400);
DISPLAY 1.021277 (-1550 2400);
PAINT ORANGE (-1550 2400);
DISPLAY INVISIBLE (-1550 2400);
FORCEPROP 2 LAST CDS_LIB mstr_standard
J 0
(-1750 2350);
PAINT ORANGE (-1750 2350);
DISPLAY INVISIBLE (-1750 2350);
FORCEPROP 1 LAST OFFPAGE TRUE
J 0
(-1425 2225);
PAINT GREEN (-1425 2225);
DISPLAY INVISIBLE (-1425 2225);
FORCEPROP 1 LAST COMMENT_BODY TRUE
J 0
(-1795 2255);
DISPLAY 1.170213 (-1795 2255);
PAINT PEACH (-1795 2255);
DISPLAY INVISIBLE (-1795 2255);
FORCEADD OFFPAGE..2
(-1750 2500);
FORCEPROP 2 LAST $XR0 185 
J 0
(-1561 2500);
DISPLAY 0.638298 (-1561 2500);
PAINT MONO (-1561 2500);
FORCEPROP 2 LAST PATH I207
J 0
(-1550 2550);
DISPLAY 1.021277 (-1550 2550);
PAINT ORANGE (-1550 2550);
DISPLAY INVISIBLE (-1550 2550);
FORCEPROP 2 LAST CDS_LIB mstr_standard
J 0
(-1750 2500);
PAINT ORANGE (-1750 2500);
DISPLAY INVISIBLE (-1750 2500);
FORCEPROP 1 LAST OFFPAGE TRUE
J 0
(-1425 2375);
PAINT GREEN (-1425 2375);
DISPLAY INVISIBLE (-1425 2375);
FORCEPROP 1 LAST COMMENT_BODY TRUE
J 0
(-1795 2405);
DISPLAY 1.170213 (-1795 2405);
PAINT PEACH (-1795 2405);
DISPLAY INVISIBLE (-1795 2405);
FORCEADD OFFPAGE..2
(-1750 2200);
FORCEPROP 2 LAST $XR0 185 
J 0
(-1561 2200);
DISPLAY 0.638298 (-1561 2200);
PAINT MONO (-1561 2200);
FORCEPROP 2 LAST PATH I208
J 0
(-1575 2275);
DISPLAY 1.021277 (-1575 2275);
PAINT ORANGE (-1575 2275);
DISPLAY INVISIBLE (-1575 2275);
FORCEPROP 2 LAST CDS_LIB mstr_standard
J 0
(-1750 2200);
PAINT ORANGE (-1750 2200);
DISPLAY INVISIBLE (-1750 2200);
FORCEPROP 1 LAST OFFPAGE TRUE
J 0
(-1425 2075);
PAINT GREEN (-1425 2075);
DISPLAY INVISIBLE (-1425 2075);
FORCEPROP 1 LAST COMMENT_BODY TRUE
J 0
(-1795 2105);
DISPLAY 1.170213 (-1795 2105);
PAINT PEACH (-1795 2105);
DISPLAY INVISIBLE (-1795 2105);
FORCEADD OFFPAGE..2
(-1750 2150);
FORCEPROP 2 LAST $XR0 185 
J 0
(-1561 2150);
DISPLAY 0.638298 (-1561 2150);
PAINT MONO (-1561 2150);
FORCEPROP 2 LAST PATH I209
J 0
(-1575 2225);
DISPLAY 1.021277 (-1575 2225);
PAINT ORANGE (-1575 2225);
DISPLAY INVISIBLE (-1575 2225);
FORCEPROP 2 LAST CDS_LIB mstr_standard
J 0
(-1750 2150);
PAINT ORANGE (-1750 2150);
DISPLAY INVISIBLE (-1750 2150);
FORCEPROP 1 LAST OFFPAGE TRUE
J 0
(-1425 2025);
PAINT GREEN (-1425 2025);
DISPLAY INVISIBLE (-1425 2025);
FORCEPROP 1 LAST COMMENT_BODY TRUE
J 0
(-1795 2055);
DISPLAY 1.170213 (-1795 2055);
PAINT PEACH (-1795 2055);
DISPLAY INVISIBLE (-1795 2055);
FORCEADD OFFPAGE..2
(-1125 2950);
FORCEPROP 2 LAST $XR0 172 
J 0
(-936 2950);
DISPLAY 0.638298 (-936 2950);
PAINT MONO (-936 2950);
FORCEPROP 2 LAST PATH I21
J 0
(-950 3025);
DISPLAY 1.361702 (-950 3025);
PAINT ORANGE (-950 3025);
DISPLAY INVISIBLE (-950 3025);
FORCEPROP 2 LAST CDS_LIB mstr_standard
J 0
(-1125 2950);
PAINT ORANGE (-1125 2950);
DISPLAY INVISIBLE (-1125 2950);
FORCEPROP 1 LAST OFFPAGE TRUE
J 0
(-800 2825);
PAINT GREEN (-800 2825);
DISPLAY INVISIBLE (-800 2825);
FORCEPROP 1 LAST COMMENT_BODY TRUE
J 0
(-1170 2855);
DISPLAY 1.170213 (-1170 2855);
PAINT PEACH (-1170 2855);
DISPLAY INVISIBLE (-1170 2855);
FORCEADD OFFPAGE..2
(-1750 2250);
FORCEPROP 2 LAST $XR0 185 
J 0
(-1561 2250);
DISPLAY 0.638298 (-1561 2250);
PAINT MONO (-1561 2250);
FORCEPROP 2 LAST PATH I210
J 0
(-1575 2325);
DISPLAY 1.021277 (-1575 2325);
PAINT ORANGE (-1575 2325);
DISPLAY INVISIBLE (-1575 2325);
FORCEPROP 2 LAST CDS_LIB mstr_standard
J 0
(-1750 2250);
PAINT ORANGE (-1750 2250);
DISPLAY INVISIBLE (-1750 2250);
FORCEPROP 1 LAST OFFPAGE TRUE
J 0
(-1425 2125);
PAINT GREEN (-1425 2125);
DISPLAY INVISIBLE (-1425 2125);
FORCEPROP 1 LAST COMMENT_BODY TRUE
J 0
(-1795 2155);
DISPLAY 1.170213 (-1795 2155);
PAINT PEACH (-1795 2155);
DISPLAY INVISIBLE (-1795 2155);
FORCEADD OFFPAGE..2
(-1750 2300);
FORCEPROP 2 LAST $XR0 185 
J 0
(-1561 2300);
DISPLAY 0.638298 (-1561 2300);
PAINT MONO (-1561 2300);
FORCEPROP 2 LAST PATH I211
J 0
(-1575 2375);
DISPLAY 1.021277 (-1575 2375);
PAINT ORANGE (-1575 2375);
DISPLAY INVISIBLE (-1575 2375);
FORCEPROP 2 LAST CDS_LIB mstr_standard
J 0
(-1750 2300);
PAINT ORANGE (-1750 2300);
DISPLAY INVISIBLE (-1750 2300);
FORCEPROP 1 LAST OFFPAGE TRUE
J 0
(-1425 2175);
PAINT GREEN (-1425 2175);
DISPLAY INVISIBLE (-1425 2175);
FORCEPROP 1 LAST COMMENT_BODY TRUE
J 0
(-1795 2205);
DISPLAY 1.170213 (-1795 2205);
PAINT PEACH (-1795 2205);
DISPLAY INVISIBLE (-1795 2205);
FORCEADD OFFPAGE..1
(-6500 2250);
FORCEPROP 2 LAST $XR0 185 
J 0
(-6752 2250);
DISPLAY 0.638298 (-6752 2250);
PAINT MONO (-6752 2250);
FORCEPROP 2 LAST CDS_LIB mstr_standard
J 0
(-6500 2250);
PAINT ORANGE (-6500 2250);
DISPLAY INVISIBLE (-6500 2250);
FORCEPROP 2 LAST PATH I212
J 0
(-6775 2300);
DISPLAY 1.021277 (-6775 2300);
PAINT ORANGE (-6775 2300);
DISPLAY INVISIBLE (-6775 2300);
FORCEPROP 1 LAST OFFPAGE TRUE
J 0
(-6175 2125);
PAINT GREEN (-6175 2125);
DISPLAY INVISIBLE (-6175 2125);
FORCEPROP 1 LAST COMMENT_BODY TRUE
J 0
(-6375 2150);
DISPLAY 1.170213 (-6375 2150);
PAINT PEACH (-6375 2150);
DISPLAY INVISIBLE (-6375 2150);
FORCEADD OFFPAGE..1
(-6500 2200);
FORCEPROP 2 LAST $XR0 185 
J 0
(-6752 2200);
DISPLAY 0.638298 (-6752 2200);
PAINT MONO (-6752 2200);
FORCEPROP 2 LAST CDS_LIB mstr_standard
J 0
(-6500 2200);
PAINT ORANGE (-6500 2200);
DISPLAY INVISIBLE (-6500 2200);
FORCEPROP 2 LAST PATH I213
J 0
(-6775 2250);
DISPLAY 1.021277 (-6775 2250);
PAINT ORANGE (-6775 2250);
DISPLAY INVISIBLE (-6775 2250);
FORCEPROP 1 LAST OFFPAGE TRUE
J 0
(-6175 2075);
PAINT GREEN (-6175 2075);
DISPLAY INVISIBLE (-6175 2075);
FORCEPROP 1 LAST COMMENT_BODY TRUE
J 0
(-6375 2100);
DISPLAY 1.170213 (-6375 2100);
PAINT PEACH (-6375 2100);
DISPLAY INVISIBLE (-6375 2100);
FORCEADD OFFPAGE..1
(-6500 2150);
FORCEPROP 2 LAST $XR0 185 
J 0
(-6752 2150);
DISPLAY 0.638298 (-6752 2150);
PAINT MONO (-6752 2150);
FORCEPROP 2 LAST CDS_LIB mstr_standard
J 0
(-6500 2150);
PAINT ORANGE (-6500 2150);
DISPLAY INVISIBLE (-6500 2150);
FORCEPROP 2 LAST PATH I214
J 0
(-6775 2200);
DISPLAY 1.021277 (-6775 2200);
PAINT ORANGE (-6775 2200);
DISPLAY INVISIBLE (-6775 2200);
FORCEPROP 1 LAST OFFPAGE TRUE
J 0
(-6175 2025);
PAINT GREEN (-6175 2025);
DISPLAY INVISIBLE (-6175 2025);
FORCEPROP 1 LAST COMMENT_BODY TRUE
J 0
(-6375 2050);
DISPLAY 1.170213 (-6375 2050);
PAINT PEACH (-6375 2050);
DISPLAY INVISIBLE (-6375 2050);
FORCEADD OFFPAGE..1
(-6500 2350);
FORCEPROP 2 LAST $XR0 185 
J 0
(-6752 2350);
DISPLAY 0.638298 (-6752 2350);
PAINT MONO (-6752 2350);
FORCEPROP 2 LAST CDS_LIB mstr_standard
J 0
(-6500 2350);
PAINT ORANGE (-6500 2350);
DISPLAY INVISIBLE (-6500 2350);
FORCEPROP 2 LAST PATH I215
J 0
(-6775 2400);
DISPLAY 1.021277 (-6775 2400);
PAINT ORANGE (-6775 2400);
DISPLAY INVISIBLE (-6775 2400);
FORCEPROP 1 LAST OFFPAGE TRUE
J 0
(-6175 2225);
PAINT GREEN (-6175 2225);
DISPLAY INVISIBLE (-6175 2225);
FORCEPROP 1 LAST COMMENT_BODY TRUE
J 0
(-6375 2250);
DISPLAY 1.170213 (-6375 2250);
PAINT PEACH (-6375 2250);
DISPLAY INVISIBLE (-6375 2250);
FORCEADD OFFPAGE..1
(-6500 2400);
FORCEPROP 2 LASTPIN (-6450 2400) SIG_NAME P3E_PCH_M2_RX_DP<2>
J 0
(-6450 2410);
DISPLAY 0.617021 (-6450 2410);
PAINT ORANGE (-6450 2410);
FORCEPROP 2 LAST $XR0 185 
J 0
(-6752 2400);
DISPLAY 0.638298 (-6752 2400);
PAINT MONO (-6752 2400);
FORCEPROP 2 LAST CDS_LIB mstr_standard
J 0
(-6500 2400);
PAINT ORANGE (-6500 2400);
DISPLAY INVISIBLE (-6500 2400);
FORCEPROP 2 LAST PATH I216
J 0
(-6775 2450);
DISPLAY 1.021277 (-6775 2450);
PAINT ORANGE (-6775 2450);
DISPLAY INVISIBLE (-6775 2450);
FORCEPROP 1 LAST OFFPAGE TRUE
J 0
(-6175 2275);
PAINT GREEN (-6175 2275);
DISPLAY INVISIBLE (-6175 2275);
FORCEPROP 1 LAST COMMENT_BODY TRUE
J 0
(-6375 2300);
DISPLAY 1.170213 (-6375 2300);
PAINT PEACH (-6375 2300);
DISPLAY INVISIBLE (-6375 2300);
FORCEADD OFFPAGE..1
(-6500 2450);
FORCEPROP 2 LASTPIN (-6450 2450) SIG_NAME P3E_PCH_M2_RX_DN<3>
J 0
(-6450 2460);
DISPLAY 0.617021 (-6450 2460);
PAINT ORANGE (-6450 2460);
FORCEPROP 2 LAST $XR0 185 
J 0
(-6752 2450);
DISPLAY 0.638298 (-6752 2450);
PAINT MONO (-6752 2450);
FORCEPROP 2 LAST CDS_LIB mstr_standard
J 0
(-6500 2450);
PAINT ORANGE (-6500 2450);
DISPLAY INVISIBLE (-6500 2450);
FORCEPROP 2 LAST PATH I217
J 0
(-6775 2500);
DISPLAY 1.021277 (-6775 2500);
PAINT ORANGE (-6775 2500);
DISPLAY INVISIBLE (-6775 2500);
FORCEPROP 1 LAST OFFPAGE TRUE
J 0
(-6175 2325);
PAINT GREEN (-6175 2325);
DISPLAY INVISIBLE (-6175 2325);
FORCEPROP 1 LAST COMMENT_BODY TRUE
J 0
(-6375 2350);
DISPLAY 1.170213 (-6375 2350);
PAINT PEACH (-6375 2350);
DISPLAY INVISIBLE (-6375 2350);
FORCEADD OFFPAGE..1
(-6500 2500);
FORCEPROP 2 LASTPIN (-6450 2500) SIG_NAME P3E_PCH_M2_RX_DP<3>
J 0
(-6450 2510);
DISPLAY 0.617021 (-6450 2510);
PAINT ORANGE (-6450 2510);
FORCEPROP 2 LAST $XR0 185 
J 0
(-6752 2500);
DISPLAY 0.638298 (-6752 2500);
PAINT MONO (-6752 2500);
FORCEPROP 2 LAST CDS_LIB mstr_standard
J 0
(-6500 2500);
PAINT ORANGE (-6500 2500);
DISPLAY INVISIBLE (-6500 2500);
FORCEPROP 2 LAST PATH I218
J 0
(-6775 2550);
DISPLAY 1.021277 (-6775 2550);
PAINT ORANGE (-6775 2550);
DISPLAY INVISIBLE (-6775 2550);
FORCEPROP 1 LAST OFFPAGE TRUE
J 0
(-6175 2375);
PAINT GREEN (-6175 2375);
DISPLAY INVISIBLE (-6175 2375);
FORCEPROP 1 LAST COMMENT_BODY TRUE
J 0
(-6375 2400);
DISPLAY 1.170213 (-6375 2400);
PAINT PEACH (-6375 2400);
DISPLAY INVISIBLE (-6375 2400);
FORCEADD OFFPAGE..1
(-6500 2300);
FORCEPROP 2 LAST $XR0 185 
J 0
(-6752 2300);
DISPLAY 0.638298 (-6752 2300);
PAINT MONO (-6752 2300);
FORCEPROP 2 LAST CDS_LIB mstr_standard
J 0
(-6500 2300);
PAINT ORANGE (-6500 2300);
DISPLAY INVISIBLE (-6500 2300);
FORCEPROP 2 LAST PATH I219
J 0
(-6775 2350);
DISPLAY 1.021277 (-6775 2350);
PAINT ORANGE (-6775 2350);
DISPLAY INVISIBLE (-6775 2350);
FORCEPROP 1 LAST OFFPAGE TRUE
J 0
(-6175 2175);
PAINT GREEN (-6175 2175);
DISPLAY INVISIBLE (-6175 2175);
FORCEPROP 1 LAST COMMENT_BODY TRUE
J 0
(-6375 2200);
DISPLAY 1.170213 (-6375 2200);
PAINT PEACH (-6375 2200);
DISPLAY INVISIBLE (-6375 2200);
FORCEADD LBG_CORE_QAT_EXT_D..3
(-4025 2850);
FORCEPROP 2 LASTPIN (-2425 3200) $PN AD70
J 0
(-2415 3210);
DISPLAY 0.617021 (-2415 3210);
PAINT ORANGE (-2415 3210);
FORCEPROP 2 LASTPIN (-2425 3150) $PN AE71
J 0
(-2415 3160);
DISPLAY 0.617021 (-2415 3160);
PAINT ORANGE (-2415 3160);
FORCEPROP 1 LAST PART_NUMBER H91415-002
J 0
(-5575 1500);
DISPLAY 0.617021 (-5575 1500);
PAINT BLUE (-5575 1500);
FORCEPROP 2 LASTPIN (-5625 2000) $PN AP69
J 2
(-5635 2010);
DISPLAY 0.617021 (-5635 2010);
PAINT ORANGE (-5635 2010);
FORCEPROP 2 LASTPIN (-5625 2050) $PN AP71
J 2
(-5635 2060);
DISPLAY 0.617021 (-5635 2060);
PAINT ORANGE (-5635 2060);
FORCEPROP 2 LASTPIN (-5625 3250) $PN AU65
J 2
(-5635 3260);
DISPLAY 0.617021 (-5635 3260);
PAINT ORANGE (-5635 3260);
FORCEPROP 1 LAST LOCATION U7C1
J 0
(-5575 4450);
DISPLAY 0.617021 (-5575 4450);
PAINT AQUA (-5575 4450);
FORCEPROP 2 LASTPIN (-2425 2700) $PN BH65
J 0
(-2415 2710);
DISPLAY 0.617021 (-2415 2710);
PAINT ORANGE (-2415 2710);
FORCEPROP 2 LASTPIN (-2425 2650) $PN BJ66
J 0
(-2415 2660);
DISPLAY 0.617021 (-2415 2660);
PAINT ORANGE (-2415 2660);
FORCEPROP 2 LASTPIN (-5625 2750) $PN AM71
J 2
(-5635 2760);
DISPLAY 0.617021 (-5635 2760);
PAINT ORANGE (-5635 2760);
FORCEPROP 2 LASTPIN (-5625 2700) $PN AM69
J 2
(-5635 2710);
DISPLAY 0.617021 (-5635 2710);
PAINT ORANGE (-5635 2710);
FORCEPROP 2 LASTPIN (-2425 2750) $PN BJ63
J 0
(-2415 2760);
DISPLAY 0.617021 (-2415 2760);
PAINT ORANGE (-2415 2760);
FORCEPROP 2 LASTPIN (-5625 1800) $PN AF58
J 2
(-5635 1810);
DISPLAY 0.617021 (-5635 1810);
PAINT ORANGE (-5635 1810);
FORCEPROP 2 LASTPIN (-5625 1850) $PN AH58
J 2
(-5635 1860);
DISPLAY 0.617021 (-5635 1860);
PAINT ORANGE (-5635 1860);
FORCEPROP 2 LASTPIN (-5625 1700) $PN BD58
J 2
(-5635 1710);
DISPLAY 0.617021 (-5635 1710);
PAINT ORANGE (-5635 1710);
FORCEPROP 2 LASTPIN (-5625 1750) $PN BB56
J 2
(-5635 1760);
DISPLAY 0.617021 (-5635 1760);
PAINT ORANGE (-5635 1760);
FORCEPROP 2 LASTPIN (-5625 2400) $PN AW69
J 2
(-5635 2410);
DISPLAY 0.617021 (-5635 2410);
PAINT ORANGE (-5635 2410);
FORCEPROP 2 LASTPIN (-5625 2350) $PN AW71
J 2
(-5635 2360);
DISPLAY 0.617021 (-5635 2360);
PAINT ORANGE (-5635 2360);
FORCEPROP 2 LASTPIN (-5625 2300) $PN AY70
J 2
(-5635 2310);
DISPLAY 0.617021 (-5635 2310);
PAINT ORANGE (-5635 2310);
FORCEPROP 2 LASTPIN (-5625 2250) $PN AY72
J 2
(-5635 2260);
DISPLAY 0.617021 (-5635 2260);
PAINT ORANGE (-5635 2260);
FORCEPROP 2 LASTPIN (-5625 2200) $PN BA69
J 2
(-5635 2210);
DISPLAY 0.617021 (-5635 2210);
PAINT ORANGE (-5635 2210);
FORCEPROP 2 LASTPIN (-5625 2150) $PN BA71
J 2
(-5635 2160);
DISPLAY 0.617021 (-5635 2160);
PAINT ORANGE (-5635 2160);
FORCEPROP 2 LASTPIN (-5625 2500) $PN AV70
J 2
(-5635 2510);
DISPLAY 0.617021 (-5635 2510);
PAINT ORANGE (-5635 2510);
FORCEPROP 2 LASTPIN (-5625 2450) $PN AV72
J 2
(-5635 2460);
DISPLAY 0.617021 (-5635 2460);
PAINT ORANGE (-5635 2460);
FORCEPROP 2 LASTPIN (-5625 2800) $PN BB63
J 2
(-5635 2810);
DISPLAY 0.617021 (-5635 2810);
PAINT ORANGE (-5635 2810);
FORCEPROP 2 LASTPIN (-5625 2650) $PN AN72
J 2
(-5635 2660);
DISPLAY 0.617021 (-5635 2660);
PAINT ORANGE (-5635 2660);
FORCEPROP 2 LASTPIN (-5625 2600) $PN AN70
J 2
(-5635 2610);
DISPLAY 0.617021 (-5635 2610);
PAINT ORANGE (-5635 2610);
FORCEPROP 2 LASTPIN (-5625 3050) $PN BD65
J 2
(-5635 3060);
DISPLAY 0.617021 (-5635 3060);
PAINT ORANGE (-5635 3060);
FORCEPROP 2 LASTPIN (-5625 3450) $PN AT63
J 2
(-5635 3460);
DISPLAY 0.617021 (-5635 3460);
PAINT ORANGE (-5635 3460);
FORCEPROP 2 LASTPIN (-5625 3200) $PN AV63
J 2
(-5635 3210);
DISPLAY 0.617021 (-5635 3210);
PAINT ORANGE (-5635 3210);
FORCEPROP 2 LASTPIN (-5625 3100) $PN AW65
J 2
(-5635 3110);
DISPLAY 0.617021 (-5635 3110);
PAINT ORANGE (-5635 3110);
FORCEPROP 2 LASTPIN (-5625 3500) $PN AL66
J 2
(-5635 3510);
DISPLAY 0.617021 (-5635 3510);
PAINT ORANGE (-5635 3510);
FORCEPROP 2 LASTPIN (-5625 3550) $PN AN65
J 2
(-5635 3560);
DISPLAY 0.617021 (-5635 3560);
PAINT ORANGE (-5635 3560);
FORCEPROP 2 LASTPIN (-5625 4000) $PN AP59
J 2
(-5635 4010);
DISPLAY 0.617021 (-5635 4010);
PAINT ORANGE (-5635 4010);
FORCEPROP 2 LASTPIN (-5625 4050) $PN AN61
J 2
(-5635 4060);
DISPLAY 0.617021 (-5635 4060);
PAINT ORANGE (-5635 4060);
FORCEPROP 2 LASTPIN (-5625 4150) $PN AD61
J 2
(-5635 4160);
DISPLAY 0.617021 (-5635 4160);
PAINT ORANGE (-5635 4160);
FORCEPROP 2 LASTPIN (-5625 4100) $PN AA61
J 2
(-5635 4110);
DISPLAY 0.617021 (-5635 4110);
PAINT ORANGE (-5635 4110);
FORCEPROP 1 LAST MATERIAL IC
J 0
(-5575 4350);
DISPLAY 0.617021 (-5575 4350);
PAINT SKYBLUE (-5575 4350);
FORCEPROP 2 LASTPIN (-2425 1750) $PN E67
J 0
(-2415 1760);
DISPLAY 0.617021 (-2415 1760);
PAINT ORANGE (-2415 1760);
FORCEPROP 2 LASTPIN (-2425 1700) $PN D66
J 0
(-2415 1710);
DISPLAY 0.617021 (-2415 1710);
PAINT ORANGE (-2415 1710);
FORCEPROP 2 LASTPIN (-2425 2000) $PN G67
J 0
(-2415 2010);
DISPLAY 0.617021 (-2415 2010);
PAINT ORANGE (-2415 2010);
FORCEPROP 2 LASTPIN (-2425 1900) $PN AA71
J 0
(-2415 1910);
DISPLAY 0.617021 (-2415 1910);
PAINT ORANGE (-2415 1910);
FORCEPROP 2 LASTPIN (-2425 1850) $PN AA69
J 0
(-2415 1860);
DISPLAY 0.617021 (-2415 1860);
PAINT ORANGE (-2415 1860);
FORCEPROP 2 LASTPIN (-2425 2050) $PN H69
J 0
(-2415 2060);
DISPLAY 0.617021 (-2415 2060);
PAINT ORANGE (-2415 2060);
FORCEPROP 2 LASTPIN (-2425 2450) $PN BH61
J 0
(-2415 2460);
DISPLAY 0.617021 (-2415 2460);
PAINT ORANGE (-2415 2460);
FORCEPROP 2 LASTPIN (-2425 2500) $PN BK61
J 0
(-2415 2510);
DISPLAY 0.617021 (-2415 2510);
PAINT ORANGE (-2415 2510);
FORCEPROP 2 LASTPIN (-2425 2150) $PN BR61
J 0
(-2415 2160);
DISPLAY 0.617021 (-2415 2160);
PAINT ORANGE (-2415 2160);
FORCEPROP 2 LASTPIN (-2425 2200) $PN BN63
J 0
(-2415 2210);
DISPLAY 0.617021 (-2415 2210);
PAINT ORANGE (-2415 2210);
FORCEPROP 2 LASTPIN (-2425 2250) $PN BM65
J 0
(-2415 2260);
DISPLAY 0.617021 (-2415 2260);
PAINT ORANGE (-2415 2260);
FORCEPROP 2 LASTPIN (-2425 2300) $PN BR65
J 0
(-2415 2310);
DISPLAY 0.617021 (-2415 2310);
PAINT ORANGE (-2415 2310);
FORCEPROP 2 LASTPIN (-2425 2350) $PN BK65
J 0
(-2415 2360);
DISPLAY 0.617021 (-2415 2360);
PAINT ORANGE (-2415 2360);
FORCEPROP 2 LASTPIN (-2425 2400) $PN BL66
J 0
(-2415 2410);
DISPLAY 0.617021 (-2415 2410);
PAINT ORANGE (-2415 2410);
FORCEPROP 2 LASTPIN (-2425 2600) $PN BG66
J 0
(-2415 2610);
DISPLAY 0.617021 (-2415 2610);
PAINT ORANGE (-2415 2610);
FORCEPROP 2 LASTPIN (-2425 2850) $PN AJ72
J 0
(-2415 2860);
DISPLAY 0.617021 (-2415 2860);
PAINT ORANGE (-2415 2860);
FORCEPROP 2 LASTPIN (-2425 2900) $PN AH69
J 0
(-2415 2910);
DISPLAY 0.617021 (-2415 2910);
PAINT ORANGE (-2415 2910);
FORCEPROP 2 LASTPIN (-2425 3450) $PN W71
J 0
(-2415 3460);
DISPLAY 0.617021 (-2415 3460);
PAINT ORANGE (-2415 3460);
FORCEPROP 2 LASTPIN (-2425 3400) $PN W69
J 0
(-2415 3410);
DISPLAY 0.617021 (-2415 3410);
PAINT ORANGE (-2415 3410);
FORCEPROP 2 LASTPIN (-2425 3250) $PN AD72
J 0
(-2415 3260);
DISPLAY 0.617021 (-2415 3260);
PAINT ORANGE (-2415 3260);
FORCEPROP 2 LASTPIN (-2425 3800) $PN P69
J 0
(-2415 3810);
DISPLAY 0.617021 (-2415 3810);
PAINT ORANGE (-2415 3810);
FORCEPROP 2 LASTPIN (-2425 3750) $PN R72
J 0
(-2415 3760);
DISPLAY 0.617021 (-2415 3760);
PAINT ORANGE (-2415 3760);
FORCEPROP 2 LASTPIN (-2425 3700) $PN R70
J 0
(-2415 3710);
DISPLAY 0.617021 (-2415 3710);
PAINT ORANGE (-2415 3710);
FORCEPROP 2 LASTPIN (-2425 3650) $PN T71
J 0
(-2415 3660);
DISPLAY 0.617021 (-2415 3660);
PAINT ORANGE (-2415 3660);
FORCEPROP 2 LASTPIN (-2425 4050) $PN M71
J 0
(-2415 4060);
DISPLAY 0.617021 (-2415 4060);
PAINT ORANGE (-2415 4060);
FORCEPROP 2 LASTPIN (-2425 4000) $PN M69
J 0
(-2415 4010);
DISPLAY 0.617021 (-2415 4010);
PAINT ORANGE (-2415 4010);
FORCEPROP 2 LASTPIN (-2425 3950) $PN N72
J 0
(-2415 3960);
DISPLAY 0.617021 (-2415 3960);
PAINT ORANGE (-2415 3960);
FORCEPROP 2 LASTPIN (-2425 3900) $PN N70
J 0
(-2415 3910);
DISPLAY 0.617021 (-2415 3910);
PAINT ORANGE (-2415 3910);
FORCEPROP 2 LASTPIN (-2425 3850) $PN P71
J 0
(-2415 3860);
DISPLAY 0.617021 (-2415 3860);
PAINT ORANGE (-2415 3860);
FORCEPROP 2 LASTPIN (-2425 4100) $PN L70
J 0
(-2415 4110);
DISPLAY 0.617021 (-2415 4110);
PAINT ORANGE (-2415 4110);
FORCEPROP 2 LASTPIN (-2425 4150) $PN L72
J 0
(-2415 4160);
DISPLAY 0.617021 (-2415 4160);
PAINT ORANGE (-2415 4160);
FORCEPROP 2 LASTPIN (-2425 2800) $PN AJ70
J 0
(-2415 2810);
DISPLAY 0.617021 (-2415 2810);
PAINT ORANGE (-2415 2810);
FORCEPROP 2 LASTPIN (-2425 3300) $PN AC69
J 0
(-2415 3310);
DISPLAY 0.617021 (-2415 3310);
PAINT ORANGE (-2415 3310);
FORCEPROP 2 LASTPIN (-2425 3350) $PN AC71
J 0
(-2415 3360);
DISPLAY 0.617021 (-2415 3360);
PAINT ORANGE (-2415 3360);
FORCEPROP 2 LASTPIN (-2425 2950) $PN AH71
J 0
(-2415 2960);
DISPLAY 0.617021 (-2415 2960);
PAINT ORANGE (-2415 2960);
FORCEPROP 2 LASTPIN (-2425 3000) $PN AF70
J 0
(-2415 3010);
DISPLAY 0.617021 (-2415 3010);
PAINT ORANGE (-2415 3010);
FORCEPROP 2 LASTPIN (-2425 3600) $PN T69
J 0
(-2415 3610);
DISPLAY 0.617021 (-2415 3610);
PAINT ORANGE (-2415 3610);
FORCEPROP 2 LASTPIN (-2425 3550) $PN V72
J 0
(-2415 3560);
DISPLAY 0.617021 (-2415 3560);
PAINT ORANGE (-2415 3560);
FORCEPROP 2 LASTPIN (-2425 3500) $PN V70
J 0
(-2415 3510);
DISPLAY 0.617021 (-2415 3510);
PAINT ORANGE (-2415 3510);
FORCEPROP 2 LASTPIN (-2425 3100) $PN AE69
J 0
(-2415 3110);
DISPLAY 0.617021 (-2415 3110);
PAINT ORANGE (-2415 3110);
FORCEPROP 2 LASTPIN (-5625 3150) $PN AY66
J 2
(-5635 3160);
DISPLAY 0.617021 (-5635 3160);
PAINT ORANGE (-5635 3160);
FORCEPROP 2 LASTPIN (-5625 3400) $PN AR61
J 2
(-5635 3410);
DISPLAY 0.617021 (-5635 3410);
PAINT ORANGE (-5635 3410);
FORCEPROP 2 LASTPIN (-5625 3900) $PN AH61
J 2
(-5635 3910);
DISPLAY 0.617021 (-5635 3910);
PAINT ORANGE (-5635 3910);
FORCEPROP 2 LASTPIN (-5625 3950) $PN AG63
J 2
(-5635 3960);
DISPLAY 0.617021 (-5635 3960);
PAINT ORANGE (-5635 3960);
FORCEPROP 2 LASTPIN (-5625 3300) $PN AT66
J 2
(-5635 3310);
DISPLAY 0.617021 (-5635 3310);
PAINT ORANGE (-5635 3310);
FORCEPROP 2 LASTPIN (-5625 2850) $PN BD61
J 2
(-5635 2860);
DISPLAY 0.617021 (-5635 2860);
PAINT ORANGE (-5635 2860);
FORCEPROP 2 LASTPIN (-5625 2900) $PN AY59
J 2
(-5635 2910);
DISPLAY 0.617021 (-5635 2910);
PAINT ORANGE (-5635 2910);
FORCEPROP 2 LASTPIN (-5625 2950) $PN BA61
J 2
(-5635 2960);
DISPLAY 0.617021 (-5635 2960);
PAINT ORANGE (-5635 2960);
FORCEPROP 2 LASTPIN (-5625 3000) $PN BA65
J 2
(-5635 3010);
DISPLAY 0.617021 (-5635 3010);
PAINT ORANGE (-5635 3010);
FORCEPROP 2 LASTPIN (-5625 3350) $PN AV66
J 2
(-5635 3360);
DISPLAY 0.617021 (-5635 3360);
PAINT ORANGE (-5635 3360);
FORCEPROP 2 LASTPIN (-5625 3650) $PN AJ63
J 2
(-5635 3660);
DISPLAY 0.617021 (-5635 3660);
PAINT ORANGE (-5635 3660);
FORCEPROP 2 LASTPIN (-5625 3700) $PN AP63
J 2
(-5635 3710);
DISPLAY 0.617021 (-5635 3710);
PAINT ORANGE (-5635 3710);
FORCEPROP 2 LASTPIN (-5625 3750) $PN AL63
J 2
(-5635 3760);
DISPLAY 0.617021 (-5635 3760);
PAINT ORANGE (-5635 3760);
FORCEPROP 2 LASTPIN (-5625 3800) $PN AF65
J 2
(-5635 3810);
DISPLAY 0.617021 (-5635 3810);
PAINT ORANGE (-5635 3810);
FORCEPROP 2 LASTPIN (-5625 3850) $PN AH65
J 2
(-5635 3860);
DISPLAY 0.617021 (-5635 3860);
PAINT ORANGE (-5635 3860);
FORCEPROP 2 LASTPIN (-5625 3600) $PN AK65
J 2
(-5635 3610);
DISPLAY 0.617021 (-5635 3610);
PAINT ORANGE (-5635 3610);
FORCEPROP 2 LASTPIN (-2425 3050) $PN AF72
J 0
(-2415 3060);
DISPLAY 0.617021 (-2415 3060);
PAINT ORANGE (-2415 3060);
FORCEPROP 2 LAST SEC_TYPE BGA1
J 0
(-5575 4500);
DISPLAY 1.021277 (-5575 4500);
PAINT ORANGE (-5575 4500);
DISPLAY INVISIBLE (-5575 4500);
FORCEPROP 2 LAST SEC 3
J 0
(-5575 4500);
DISPLAY 0.680851 (-5575 4500);
PAINT MONO (-5575 4500);
DISPLAY INVISIBLE (-5575 4500);
FORCEPROP 0 LAST BOM_COST SB
J 0
(-5975 4900);
DISPLAY 1.361702 (-5975 4900);
PAINT ORANGE (-5975 4900);
DISPLAY INVISIBLE (-5975 4900);
FORCEPROP 2 LAST CDS_LOCATION U7C1
J 0
(-5575 4450);
DISPLAY 0.617021 (-5575 4450);
PAINT AQUA (-5575 4450);
DISPLAY INVISIBLE (-5575 4450);
FORCEPROP 0 LAST ROOM SB
J 0
(-5975 4800);
DISPLAY 1.361702 (-5975 4800);
PAINT ORANGE (-5975 4800);
DISPLAY INVISIBLE (-5975 4800);
FORCEPROP 1 LAST PACK_TYPE BGA1
J 0
(-5575 4450);
PAINT SKYBLUE (-5575 4450);
DISPLAY INVISIBLE (-5575 4450);
FORCEPROP 2 LAST CDS_LIB mstr_u_proc
J 0
(-4025 2850);
PAINT ORANGE (-4025 2850);
DISPLAY INVISIBLE (-4025 2850);
FORCEPROP 1 LAST PATH I220
J 0
(-4025 4350);
PAINT GREEN (-4025 4350);
DISPLAY INVISIBLE (-4025 4350);
FORCEADD OFFPAGE..2
(-925 4175);
FORCEPROP 2 LAST $XR0 173 
J 0
(-736 4175);
DISPLAY 0.638298 (-736 4175);
PAINT MONO (-736 4175);
FORCEPROP 2 LAST PATH I221
J 0
(-750 4250);
DISPLAY 1.021277 (-750 4250);
PAINT ORANGE (-750 4250);
DISPLAY INVISIBLE (-750 4250);
FORCEPROP 2 LAST CDS_LIB mstr_standard
J 0
(-925 4175);
PAINT ORANGE (-925 4175);
DISPLAY INVISIBLE (-925 4175);
FORCEPROP 1 LAST OFFPAGE TRUE
J 0
(-600 4050);
PAINT GREEN (-600 4050);
DISPLAY INVISIBLE (-600 4050);
FORCEPROP 1 LAST COMMENT_BODY TRUE
J 0
(-970 4080);
DISPLAY 1.170213 (-970 4080);
PAINT PEACH (-970 4080);
DISPLAY INVISIBLE (-970 4080);
FORCEADD OFFPAGE..2
(-925 4225);
FORCEPROP 2 LAST $XR0 173 
J 0
(-736 4225);
DISPLAY 0.638298 (-736 4225);
PAINT MONO (-736 4225);
FORCEPROP 2 LAST PATH I222
J 0
(-750 4300);
DISPLAY 1.021277 (-750 4300);
PAINT ORANGE (-750 4300);
DISPLAY INVISIBLE (-750 4300);
FORCEPROP 2 LAST CDS_LIB mstr_standard
J 0
(-925 4225);
PAINT ORANGE (-925 4225);
DISPLAY INVISIBLE (-925 4225);
FORCEPROP 1 LAST OFFPAGE TRUE
J 0
(-600 4100);
PAINT GREEN (-600 4100);
DISPLAY INVISIBLE (-600 4100);
FORCEPROP 1 LAST COMMENT_BODY TRUE
J 0
(-970 4130);
DISPLAY 1.170213 (-970 4130);
PAINT PEACH (-970 4130);
DISPLAY INVISIBLE (-970 4130);
FORCEADD OFFPAGE..1
(-7450 4250);
FORCEPROP 2 LAST $XR0 173 
J 0
(-7732 4250);
DISPLAY 0.638298 (-7732 4250);
PAINT MONO (-7732 4250);
FORCEPROP 2 LAST PATH I223
J 0
(-7400 4325);
DISPLAY 1.021277 (-7400 4325);
PAINT ORANGE (-7400 4325);
DISPLAY INVISIBLE (-7400 4325);
FORCEPROP 2 LAST CDS_LIB mstr_standard
J 0
(-7450 4250);
PAINT ORANGE (-7450 4250);
DISPLAY INVISIBLE (-7450 4250);
FORCEPROP 1 LAST OFFPAGE TRUE
J 0
(-7125 4125);
PAINT GREEN (-7125 4125);
DISPLAY INVISIBLE (-7125 4125);
FORCEPROP 1 LAST COMMENT_BODY TRUE
J 0
(-7325 4150);
DISPLAY 1.170213 (-7325 4150);
PAINT PEACH (-7325 4150);
DISPLAY INVISIBLE (-7325 4150);
FORCEADD OFFPAGE..1
(-7450 4300);
FORCEPROP 2 LAST $XR0 173 
J 0
(-7732 4300);
DISPLAY 0.638298 (-7732 4300);
PAINT MONO (-7732 4300);
FORCEPROP 2 LAST PATH I224
J 0
(-7400 4375);
DISPLAY 1.021277 (-7400 4375);
PAINT ORANGE (-7400 4375);
DISPLAY INVISIBLE (-7400 4375);
FORCEPROP 2 LAST CDS_LIB mstr_standard
J 0
(-7450 4300);
PAINT ORANGE (-7450 4300);
DISPLAY INVISIBLE (-7450 4300);
FORCEPROP 1 LAST OFFPAGE TRUE
J 0
(-7125 4175);
PAINT GREEN (-7125 4175);
DISPLAY INVISIBLE (-7125 4175);
FORCEPROP 1 LAST COMMENT_BODY TRUE
J 0
(-7325 4200);
DISPLAY 1.170213 (-7325 4200);
PAINT PEACH (-7325 4200);
DISPLAY INVISIBLE (-7325 4200);
FORCEADD RES..2
(-2125 1400);
FORCEPROP 1 LAST PART_NUMBER G21796-016
J 0
(-2085 1275);
DISPLAY 0.617021 (-2085 1275);
PAINT BLUE (-2085 1275);
FORCEPROP 1 LAST PACK_TYPE 0402
J 0
(-2085 1225);
DISPLAY 0.617021 (-2085 1225);
PAINT SKYBLUE (-2085 1225);
FORCEPROP 1 LASTPIN (-2125 1300) $PN 2
J 0
(-2120 1310);
DISPLAY 0.617021 (-2120 1310);
PAINT ORANGE (-2120 1310);
FORCEPROP 1 LAST MATERIAL EMPTY
J 0
(-2085 1325);
DISPLAY 0.617021 (-2085 1325);
PAINT RED (-2085 1325);
FORCEPROP 1 LAST WATTAGE 1/16W
J 0
(-2085 1375);
DISPLAY 0.617021 (-2085 1375);
PAINT SKYBLUE (-2085 1375);
FORCEPROP 1 LAST VALUE 10.0K
J 0
(-2080 1475);
DISPLAY 0.617021 (-2080 1475);
PAINT SKYBLUE (-2080 1475);
FORCEPROP 1 LAST LOCATION R7B8
J 0
(-2080 1525);
DISPLAY 0.617021 (-2080 1525);
PAINT AQUA (-2080 1525);
FORCEPROP 1 LAST TOLERANCE 1%
J 0
(-2080 1425);
DISPLAY 0.617021 (-2080 1425);
PAINT SKYBLUE (-2080 1425);
FORCEPROP 1 LASTPIN (-2125 1500) $PN 1
J 0
(-2120 1462);
DISPLAY 0.617021 (-2120 1462);
PAINT ORANGE (-2120 1462);
FORCEPROP 2 LAST ROOM SB
J 0
(-2175 1550);
DISPLAY 1.617021 (-2175 1550);
PAINT WHITE (-2175 1550);
DISPLAY INVISIBLE (-2175 1550);
FORCEPROP 2 LAST SEC 1
J 0
(-2075 1625);
DISPLAY 0.680851 (-2075 1625);
PAINT MONO (-2075 1625);
DISPLAY INVISIBLE (-2075 1625);
FORCEPROP 2 LAST SEC_TYPE 0402
J 0
(-2075 1625);
DISPLAY 1.021277 (-2075 1625);
PAINT ORANGE (-2075 1625);
DISPLAY INVISIBLE (-2075 1625);
FORCEPROP 1 LAST PATH I229
J 0
(-2075 1575);
DISPLAY 0.978723 (-2075 1575);
PAINT WHITE (-2075 1575);
DISPLAY INVISIBLE (-2075 1575);
FORCEPROP 2 LAST CDS_LOCATION R7B8
J 0
(-2080 1525);
DISPLAY 0.617021 (-2080 1525);
PAINT AQUA (-2080 1525);
DISPLAY INVISIBLE (-2080 1525);
FORCEPROP 2 LAST CDS_LIB mstr_discrete
J 0
(-2125 1400);
PAINT ORANGE (-2125 1400);
DISPLAY INVISIBLE (-2125 1400);
FORCEADD RES..2
(-1825 1400);
FORCEPROP 1 LAST WATTAGE 1/16W
J 0
(-1785 1375);
DISPLAY 0.617021 (-1785 1375);
PAINT SKYBLUE (-1785 1375);
FORCEPROP 1 LAST MATERIAL EMPTY
J 0
(-1785 1325);
DISPLAY 0.617021 (-1785 1325);
PAINT RED (-1785 1325);
FORCEPROP 1 LAST PART_NUMBER G21796-016
J 0
(-1785 1275);
DISPLAY 0.617021 (-1785 1275);
PAINT BLUE (-1785 1275);
FORCEPROP 1 LAST VALUE 10.0K
J 0
(-1780 1475);
DISPLAY 0.617021 (-1780 1475);
PAINT SKYBLUE (-1780 1475);
FORCEPROP 1 LASTPIN (-1825 1500) $PN 1
J 0
(-1820 1462);
DISPLAY 0.617021 (-1820 1462);
PAINT ORANGE (-1820 1462);
FORCEPROP 1 LAST LOCATION R7B7
J 0
(-1780 1525);
DISPLAY 0.617021 (-1780 1525);
PAINT AQUA (-1780 1525);
FORCEPROP 1 LAST TOLERANCE 1%
J 0
(-1780 1425);
DISPLAY 0.617021 (-1780 1425);
PAINT SKYBLUE (-1780 1425);
FORCEPROP 1 LAST PACK_TYPE 0402
J 0
(-1785 1225);
DISPLAY 0.617021 (-1785 1225);
PAINT SKYBLUE (-1785 1225);
FORCEPROP 1 LASTPIN (-1825 1300) $PN 2
J 0
(-1820 1310);
DISPLAY 0.617021 (-1820 1310);
PAINT ORANGE (-1820 1310);
FORCEPROP 1 LAST PATH I230
J 0
(-1775 1575);
DISPLAY 0.978723 (-1775 1575);
PAINT WHITE (-1775 1575);
DISPLAY INVISIBLE (-1775 1575);
FORCEPROP 2 LAST SEC_TYPE 0402
J 0
(-1775 1625);
DISPLAY 1.021277 (-1775 1625);
PAINT ORANGE (-1775 1625);
DISPLAY INVISIBLE (-1775 1625);
FORCEPROP 2 LAST SEC 1
J 0
(-1775 1625);
DISPLAY 0.680851 (-1775 1625);
PAINT MONO (-1775 1625);
DISPLAY INVISIBLE (-1775 1625);
FORCEPROP 2 LAST ROOM SB
J 0
(-1875 1550);
DISPLAY 1.617021 (-1875 1550);
PAINT WHITE (-1875 1550);
DISPLAY INVISIBLE (-1875 1550);
FORCEPROP 2 LAST CDS_LOCATION R7B7
J 0
(-1780 1525);
DISPLAY 0.617021 (-1780 1525);
PAINT AQUA (-1780 1525);
DISPLAY INVISIBLE (-1780 1525);
FORCEPROP 2 LAST CDS_LIB mstr_discrete
J 0
(-1825 1400);
PAINT ORANGE (-1825 1400);
DISPLAY INVISIBLE (-1825 1400);
FORCEADD GND..1
(-1925 1000);
FORCEPROP 3 LASTPIN (-1925 1050) SIG_NAME GND\g
J 0
(-1915 1060);
DISPLAY 0.659574 (-1915 1060);
PAINT MONO (-1915 1060);
DISPLAY INVISIBLE (-1915 1060);
FORCEPROP 2 LAST CDS_LIB mstr_symbols
J 0
(-1925 1000);
PAINT ORANGE (-1925 1000);
DISPLAY INVISIBLE (-1925 1000);
FORCEPROP 1 LAST PATH I231
J 0
(-1850 1000);
DISPLAY 0.872340 (-1850 1000);
PAINT AQUA (-1850 1000);
DISPLAY INVISIBLE (-1850 1000);
FORCEPROP 1 LAST SIZE 1B
J 0
(-1850 950);
DISPLAY 0.872340 (-1850 950);
PAINT AQUA (-1850 950);
DISPLAY INVISIBLE (-1850 950);
FORCEPROP 1 LAST VOLTAGE 0.0V
J 0
(-1970 957);
DISPLAY 0.340426 (-1970 957);
PAINT SKYBLUE (-1970 957);
DISPLAY INVISIBLE (-1970 957);
FORCEPROP 1 LAST BODY_TYPE PLUMBING
J 0
(-1970 957);
DISPLAY 0.340426 (-1970 957);
PAINT GREEN (-1970 957);
DISPLAY INVISIBLE (-1970 957);
FORCEPROP 1 LAST HDL_POWER GND
J 0
(-1925 1150);
DISPLAY 0.872340 (-1925 1150);
PAINT GREEN (-1925 1150);
DISPLAY INVISIBLE (-1925 1150);
FORCEADD OFFPAGE..1
(-7200 1050);
FORCEPROP 2 LAST $XR1 116 
J 0
(-7572 1050);
DISPLAY 0.638298 (-7572 1050);
PAINT MONO (-7572 1050);
FORCEPROP 2 LAST $XR0 145 
J 0
(-7452 1050);
DISPLAY 0.638298 (-7452 1050);
PAINT MONO (-7452 1050);
FORCEPROP 2 LAST PATH I232
J 0
(-7150 1125);
DISPLAY 1.021277 (-7150 1125);
PAINT ORANGE (-7150 1125);
DISPLAY INVISIBLE (-7150 1125);
FORCEPROP 2 LAST CDS_LIB mstr_standard
J 0
(-7200 1050);
PAINT ORANGE (-7200 1050);
DISPLAY INVISIBLE (-7200 1050);
FORCEPROP 1 LAST OFFPAGE TRUE
J 0
(-6875 925);
DISPLAY 0.872340 (-6875 925);
PAINT GREEN (-6875 925);
DISPLAY INVISIBLE (-6875 925);
FORCEPROP 1 LAST COMMENT_BODY TRUE
J 0
(-7075 950);
DISPLAY 0.872340 (-7075 950);
PAINT GREEN (-7075 950);
DISPLAY INVISIBLE (-7075 950);
FORCEADD OFFPAGE..1
(-7200 950);
FORCEPROP 2 LAST $XR1 116 
J 0
(-7572 950);
DISPLAY 0.638298 (-7572 950);
PAINT MONO (-7572 950);
FORCEPROP 2 LAST $XR0 145 
J 0
(-7452 950);
DISPLAY 0.638298 (-7452 950);
PAINT MONO (-7452 950);
FORCEPROP 2 LAST CDS_LIB mstr_standard
J 0
(-7200 950);
PAINT ORANGE (-7200 950);
DISPLAY INVISIBLE (-7200 950);
FORCEPROP 2 LAST PATH I233
J 0
(-7150 1025);
DISPLAY 1.021277 (-7150 1025);
PAINT ORANGE (-7150 1025);
DISPLAY INVISIBLE (-7150 1025);
FORCEPROP 1 LAST OFFPAGE TRUE
J 0
(-6875 825);
DISPLAY 0.872340 (-6875 825);
PAINT GREEN (-6875 825);
DISPLAY INVISIBLE (-6875 825);
FORCEPROP 1 LAST COMMENT_BODY TRUE
J 0
(-7075 850);
DISPLAY 0.872340 (-7075 850);
PAINT GREEN (-7075 850);
DISPLAY INVISIBLE (-7075 850);
FORCEADD RES..2
(-6250 750);
FORCEPROP 0 LAST POP NOPOP
J 0
(-6200 525);
DISPLAY 0.638298 (-6200 525);
PAINT RED (-6200 525);
FORCEPROP 1 LAST PART_NUMBER G21796-010
J 0
(-6210 625);
DISPLAY 0.617021 (-6210 625);
PAINT BLUE (-6210 625);
FORCEPROP 1 LAST PACK_TYPE 0402
J 0
(-6210 575);
DISPLAY 0.617021 (-6210 575);
PAINT SKYBLUE (-6210 575);
FORCEPROP 1 LAST TOLERANCE 1%
J 0
(-6205 775);
DISPLAY 0.617021 (-6205 775);
PAINT SKYBLUE (-6205 775);
FORCEPROP 1 LAST WATTAGE 1/16W
J 0
(-6210 725);
DISPLAY 0.617021 (-6210 725);
PAINT SKYBLUE (-6210 725);
FORCEPROP 1 LAST MATERIAL CHIP
J 0
(-6210 675);
DISPLAY 0.617021 (-6210 675);
PAINT SKYBLUE (-6210 675);
FORCEPROP 1 LAST LOCATION R3M9
J 0
(-6205 875);
DISPLAY 0.617021 (-6205 875);
PAINT AQUA (-6205 875);
FORCEPROP 1 LAST VALUE 100.0K
J 0
(-6205 825);
DISPLAY 0.617021 (-6205 825);
PAINT SKYBLUE (-6205 825);
FORCEPROP 1 LASTPIN (-6250 650) $PN 2
J 0
(-6245 660);
DISPLAY 0.787234 (-6245 660);
PAINT ORANGE (-6245 660);
DISPLAY INVISIBLE (-6245 660);
FORCEPROP 2 LAST CDS_LIB mstr_discrete
J 0
(-6250 750);
PAINT ORANGE (-6250 750);
DISPLAY INVISIBLE (-6250 750);
FORCEPROP 1 LASTPIN (-6250 850) $PN 1
J 0
(-6245 812);
DISPLAY 0.787234 (-6245 812);
PAINT ORANGE (-6245 812);
DISPLAY INVISIBLE (-6245 812);
FORCEPROP 0 LAST ROOM SB
J 0
(-6200 975);
DISPLAY 1.021277 (-6200 975);
PAINT ORANGE (-6200 975);
DISPLAY INVISIBLE (-6200 975);
FORCEPROP 1 LAST PATH I234
J 0
(-6200 925);
DISPLAY 0.978723 (-6200 925);
PAINT WHITE (-6200 925);
DISPLAY INVISIBLE (-6200 925);
FORCEPROP 2 LAST CDS_SEC 1
J 0
(-6200 975);
PAINT MONO (-6200 975);
DISPLAY INVISIBLE (-6200 975);
FORCEPROP 2 LAST $SEC 1
J 0
(-6200 975);
PAINT MONO (-6200 975);
DISPLAY INVISIBLE (-6200 975);
FORCEPROP 2 LAST CDS_LOCATION R3M9
J 0
(-6205 875);
DISPLAY 0.617021 (-6205 875);
PAINT AQUA (-6205 875);
DISPLAY INVISIBLE (-6205 875);
FORCEADD RES..2
(-5900 750);
FORCEPROP 0 LAST POP NOPOP
J 0
(-5850 525);
DISPLAY 0.638298 (-5850 525);
PAINT RED (-5850 525);
FORCEPROP 1 LAST PACK_TYPE 0402
J 0
(-5860 575);
DISPLAY 0.617021 (-5860 575);
PAINT SKYBLUE (-5860 575);
FORCEPROP 1 LAST PART_NUMBER G21796-010
J 0
(-5860 625);
DISPLAY 0.617021 (-5860 625);
PAINT BLUE (-5860 625);
FORCEPROP 1 LAST MATERIAL CHIP
J 0
(-5860 675);
DISPLAY 0.617021 (-5860 675);
PAINT SKYBLUE (-5860 675);
FORCEPROP 1 LAST VALUE 100.0K
J 0
(-5855 825);
DISPLAY 0.617021 (-5855 825);
PAINT SKYBLUE (-5855 825);
FORCEPROP 1 LAST WATTAGE 1/16W
J 0
(-5860 725);
DISPLAY 0.617021 (-5860 725);
PAINT SKYBLUE (-5860 725);
FORCEPROP 1 LAST TOLERANCE 1%
J 0
(-5855 775);
DISPLAY 0.617021 (-5855 775);
PAINT SKYBLUE (-5855 775);
FORCEPROP 1 LAST LOCATION R3M8
J 0
(-5855 875);
DISPLAY 0.617021 (-5855 875);
PAINT AQUA (-5855 875);
FORCEPROP 1 LASTPIN (-5900 650) $PN 2
J 0
(-5895 660);
DISPLAY 0.787234 (-5895 660);
PAINT ORANGE (-5895 660);
DISPLAY INVISIBLE (-5895 660);
FORCEPROP 1 LASTPIN (-5900 850) $PN 1
J 0
(-5895 812);
DISPLAY 0.787234 (-5895 812);
PAINT ORANGE (-5895 812);
DISPLAY INVISIBLE (-5895 812);
FORCEPROP 2 LAST CDS_LIB mstr_discrete
J 0
(-5900 750);
PAINT ORANGE (-5900 750);
DISPLAY INVISIBLE (-5900 750);
FORCEPROP 1 LAST PATH I235
J 0
(-5850 925);
DISPLAY 0.978723 (-5850 925);
PAINT WHITE (-5850 925);
DISPLAY INVISIBLE (-5850 925);
FORCEPROP 2 LAST CDS_LOCATION R3M8
J 0
(-5855 875);
DISPLAY 0.617021 (-5855 875);
PAINT AQUA (-5855 875);
DISPLAY INVISIBLE (-5855 875);
FORCEPROP 2 LAST $SEC 1
J 0
(-5850 975);
PAINT MONO (-5850 975);
DISPLAY INVISIBLE (-5850 975);
FORCEPROP 0 LAST ROOM SB
J 0
(-5850 975);
DISPLAY 1.021277 (-5850 975);
PAINT ORANGE (-5850 975);
DISPLAY INVISIBLE (-5850 975);
FORCEPROP 2 LAST CDS_SEC 1
J 0
(-5850 975);
PAINT MONO (-5850 975);
DISPLAY INVISIBLE (-5850 975);
FORCEADD GND..1
(-6250 475);
FORCEPROP 3 LASTPIN (-6250 525) SIG_NAME GND\g
J 0
(-6240 535);
DISPLAY 0.659574 (-6240 535);
PAINT MONO (-6240 535);
DISPLAY INVISIBLE (-6240 535);
FORCEPROP 1 LAST VOLTAGE 0.0V
J 0
(-6295 432);
DISPLAY 0.340426 (-6295 432);
PAINT SKYBLUE (-6295 432);
DISPLAY INVISIBLE (-6295 432);
FORCEPROP 1 LAST PATH I236
J 0
(-6175 475);
DISPLAY 0.872340 (-6175 475);
PAINT AQUA (-6175 475);
DISPLAY INVISIBLE (-6175 475);
FORCEPROP 2 LAST CDS_LIB mstr_symbols
J 0
(-6250 475);
PAINT ORANGE (-6250 475);
DISPLAY INVISIBLE (-6250 475);
FORCEPROP 1 LAST SIZE 1B
J 0
(-6175 425);
DISPLAY 0.872340 (-6175 425);
PAINT AQUA (-6175 425);
DISPLAY INVISIBLE (-6175 425);
FORCEPROP 1 LAST BODY_TYPE PLUMBING
J 0
(-6295 432);
DISPLAY 0.340426 (-6295 432);
PAINT GREEN (-6295 432);
DISPLAY INVISIBLE (-6295 432);
FORCEPROP 1 LAST HDL_POWER GND
J 0
(-6250 625);
DISPLAY 0.872340 (-6250 625);
PAINT GREEN (-6250 625);
DISPLAY INVISIBLE (-6250 625);
FORCEADD GND..1
(-5900 475);
FORCEPROP 3 LASTPIN (-5900 525) SIG_NAME GND\g
J 0
(-5890 535);
DISPLAY 0.659574 (-5890 535);
PAINT MONO (-5890 535);
DISPLAY INVISIBLE (-5890 535);
FORCEPROP 1 LAST VOLTAGE 0.0V
J 0
(-5945 432);
DISPLAY 0.340426 (-5945 432);
PAINT SKYBLUE (-5945 432);
DISPLAY INVISIBLE (-5945 432);
FORCEPROP 1 LAST PATH I237
J 0
(-5825 475);
DISPLAY 0.872340 (-5825 475);
PAINT AQUA (-5825 475);
DISPLAY INVISIBLE (-5825 475);
FORCEPROP 2 LAST CDS_LIB mstr_symbols
J 0
(-5900 475);
PAINT ORANGE (-5900 475);
DISPLAY INVISIBLE (-5900 475);
FORCEPROP 1 LAST SIZE 1B
J 0
(-5825 425);
DISPLAY 0.872340 (-5825 425);
PAINT AQUA (-5825 425);
DISPLAY INVISIBLE (-5825 425);
FORCEPROP 1 LAST BODY_TYPE PLUMBING
J 0
(-5945 432);
DISPLAY 0.340426 (-5945 432);
PAINT GREEN (-5945 432);
DISPLAY INVISIBLE (-5945 432);
FORCEPROP 1 LAST HDL_POWER GND
J 0
(-5900 625);
DISPLAY 0.872340 (-5900 625);
PAINT GREEN (-5900 625);
DISPLAY INVISIBLE (-5900 625);
FORCEADD CAP_A..1
R 1
(-1725 2650);
FORCEPROP 1 LAST PACK_TYPE 0402V
J 0
(-1550 2550);
DISPLAY 0.617021 (-1550 2550);
PAINT SKYBLUE (-1550 2550);
FORCEPROP 1 LAST MATERIAL X7R
J 0
(-1650 2550);
DISPLAY 0.617021 (-1650 2550);
PAINT SKYBLUE (-1650 2550);
FORCEPROP 1 LAST VOLTAGE 16V
J 0
(-1775 2550);
DISPLAY 0.617021 (-1775 2550);
PAINT SKYBLUE (-1775 2550);
FORCEPROP 1 LAST PART_NUMBER A36096-030
J 0
(-1925 2700);
DISPLAY 0.617021 (-1925 2700);
PAINT BLUE (-1925 2700);
FORCEPROP 1 LASTPIN (-1825 2650) $PN 1
J 0
(-1855 2660);
DISPLAY 0.617021 (-1855 2660);
PAINT MONO (-1855 2660);
FORCEPROP 1 LASTPIN (-1625 2650) $PN 2
J 0
(-1605 2660);
DISPLAY 0.617021 (-1605 2660);
PAINT MONO (-1605 2660);
FORCEPROP 1 LAST VALUE 0.1UF
J 0
(-2050 2550);
DISPLAY 0.617021 (-2050 2550);
PAINT SKYBLUE (-2050 2550);
FORCEPROP 1 LAST TOLERANCE 10%
J 0
(-1900 2550);
DISPLAY 0.617021 (-1900 2550);
PAINT SKYBLUE (-1900 2550);
FORCEPROP 1 LAST LOCATION C2M4
J 0
(-2200 2550);
DISPLAY 0.617021 (-2200 2550);
PAINT AQUA (-2200 2550);
FORCEPROP 0 LAST GROUP AST2500
J 0
(-1850 2600);
DISPLAY 0.638298 (-1850 2600);
PAINT BROWN (-1850 2600);
DISPLAY BOTH (-1850 2600);
FORCEPROP 2 LAST CDS_LOCATION C2M4
R 1
J 0
(-1825 2700);
DISPLAY 0.617021 (-1825 2700);
PAINT AQUA (-1825 2700);
DISPLAY INVISIBLE (-1825 2700);
FORCEPROP 1 LAST PATH I238
R 1
J 0
(-1875 2700);
DISPLAY 0.978723 (-1875 2700);
PAINT WHITE (-1875 2700);
DISPLAY INVISIBLE (-1875 2700);
FORCEPROP 2 LAST SEC 1
R 1
J 0
(-1925 2700);
DISPLAY 0.936170 (-1925 2700);
PAINT MONO (-1925 2700);
DISPLAY INVISIBLE (-1925 2700);
FORCEPROP 2 LAST SEC_TYPE 0402V
R 1
J 0
(-1925 2700);
PAINT MONO (-1925 2700);
DISPLAY INVISIBLE (-1925 2700);
FORCEPROP 2 LAST CDS_SEC 1
R 1
J 0
(-1875 2700);
PAINT ORANGE (-1875 2700);
DISPLAY INVISIBLE (-1875 2700);
FORCEPROP 2 LAST CDS_LIB dev_discrete
R 1
J 0
(-1725 2650);
PAINT ORANGE (-1725 2650);
DISPLAY INVISIBLE (-1725 2650);
FORCEPROP 2 LAST BOM_COST PROC_SIDEBAND
R 1
J 0
(-1725 2650);
PAINT MONO (-1725 2650);
DISPLAY INVISIBLE (-1725 2650);
FORCEPROP 2 LAST ROOM PROC_SIDEBAND
R 1
J 0
(-1475 2700);
DISPLAY 0.978723 (-1475 2700);
PAINT ORANGE (-1475 2700);
DISPLAY INVISIBLE (-1475 2700);
FORCEADD CAP_A..1
R 1
(-1325 2600);
FORCEPROP 1 LAST VALUE 0.1UF
J 0
(-1425 2525);
DISPLAY 0.617021 (-1425 2525);
PAINT SKYBLUE (-1425 2525);
FORCEPROP 1 LAST LOCATION C2M3
J 0
(-1425 2675);
DISPLAY 0.617021 (-1425 2675);
PAINT AQUA (-1425 2675);
FORCEPROP 1 LASTPIN (-1425 2600) $PN 1
J 0
(-1455 2610);
DISPLAY 0.617021 (-1455 2610);
PAINT MONO (-1455 2610);
FORCEPROP 1 LAST PART_NUMBER A36096-030
J 0
(-1425 2325);
DISPLAY 0.617021 (-1425 2325);
PAINT BLUE (-1425 2325);
FORCEPROP 1 LASTPIN (-1225 2600) $PN 2
J 0
(-1205 2610);
DISPLAY 0.617021 (-1205 2610);
PAINT MONO (-1205 2610);
FORCEPROP 1 LAST VOLTAGE 16V
J 0
(-1425 2425);
DISPLAY 0.617021 (-1425 2425);
PAINT SKYBLUE (-1425 2425);
FORCEPROP 1 LAST MATERIAL X7R
J 0
(-1425 2375);
DISPLAY 0.617021 (-1425 2375);
PAINT SKYBLUE (-1425 2375);
FORCEPROP 1 LAST PACK_TYPE 0402V
J 0
(-1425 2275);
DISPLAY 0.617021 (-1425 2275);
PAINT SKYBLUE (-1425 2275);
FORCEPROP 1 LAST TOLERANCE 10%
J 0
(-1425 2475);
DISPLAY 0.617021 (-1425 2475);
PAINT SKYBLUE (-1425 2475);
FORCEPROP 0 LAST GROUP AST2500
J 0
(-1300 2525);
DISPLAY 0.638298 (-1300 2525);
PAINT BROWN (-1300 2525);
DISPLAY BOTH (-1300 2525);
FORCEPROP 2 LAST CDS_LOCATION C2M3
R 1
J 0
(-1425 2650);
DISPLAY 0.617021 (-1425 2650);
PAINT AQUA (-1425 2650);
DISPLAY INVISIBLE (-1425 2650);
FORCEPROP 1 LAST PATH I239
R 1
J 0
(-1475 2650);
DISPLAY 0.978723 (-1475 2650);
PAINT WHITE (-1475 2650);
DISPLAY INVISIBLE (-1475 2650);
FORCEPROP 2 LAST SEC 1
R 1
J 0
(-1525 2650);
DISPLAY 0.936170 (-1525 2650);
PAINT MONO (-1525 2650);
DISPLAY INVISIBLE (-1525 2650);
FORCEPROP 2 LAST SEC_TYPE 0402V
R 1
J 0
(-1525 2650);
PAINT MONO (-1525 2650);
DISPLAY INVISIBLE (-1525 2650);
FORCEPROP 2 LAST CDS_SEC 1
R 1
J 0
(-1475 2650);
PAINT ORANGE (-1475 2650);
DISPLAY INVISIBLE (-1475 2650);
FORCEPROP 2 LAST CDS_LIB dev_discrete
R 1
J 0
(-1325 2600);
PAINT ORANGE (-1325 2600);
DISPLAY INVISIBLE (-1325 2600);
FORCEPROP 2 LAST BOM_COST PROC_SIDEBAND
R 1
J 0
(-1325 2600);
PAINT MONO (-1325 2600);
DISPLAY INVISIBLE (-1325 2600);
FORCEPROP 2 LAST ROOM PROC_SIDEBAND
R 1
J 0
(-1075 2650);
DISPLAY 0.978723 (-1075 2650);
PAINT ORANGE (-1075 2650);
DISPLAY INVISIBLE (-1075 2650);
FORCEADD OFFPAGE..2
(-1125 2700);
FORCEPROP 2 LAST $XR0 139 
J 0
(-936 2700);
DISPLAY 0.638298 (-936 2700);
PAINT MONO (-936 2700);
FORCEPROP 2 LAST PATH I26
J 0
(-950 2775);
DISPLAY 1.361702 (-950 2775);
PAINT ORANGE (-950 2775);
DISPLAY INVISIBLE (-950 2775);
FORCEPROP 2 LAST CDS_LIB mstr_standard
J 0
(-1125 2700);
PAINT ORANGE (-1125 2700);
DISPLAY INVISIBLE (-1125 2700);
FORCEPROP 1 LAST OFFPAGE TRUE
J 0
(-800 2575);
PAINT GREEN (-800 2575);
DISPLAY INVISIBLE (-800 2575);
FORCEPROP 1 LAST COMMENT_BODY TRUE
J 0
(-1170 2605);
DISPLAY 1.170213 (-1170 2605);
PAINT PEACH (-1170 2605);
DISPLAY INVISIBLE (-1170 2605);
FORCEADD OFFPAGE..2
(-1125 2750);
FORCEPROP 2 LAST $XR0 139 
J 0
(-936 2750);
DISPLAY 0.638298 (-936 2750);
PAINT MONO (-936 2750);
FORCEPROP 2 LAST PATH I27
J 0
(-950 2825);
DISPLAY 1.361702 (-950 2825);
PAINT ORANGE (-950 2825);
DISPLAY INVISIBLE (-950 2825);
FORCEPROP 2 LAST CDS_LIB mstr_standard
J 0
(-1125 2750);
PAINT ORANGE (-1125 2750);
DISPLAY INVISIBLE (-1125 2750);
FORCEPROP 1 LAST OFFPAGE TRUE
J 0
(-800 2625);
PAINT GREEN (-800 2625);
DISPLAY INVISIBLE (-800 2625);
FORCEPROP 1 LAST COMMENT_BODY TRUE
J 0
(-1170 2655);
DISPLAY 1.170213 (-1170 2655);
PAINT PEACH (-1170 2655);
DISPLAY INVISIBLE (-1170 2655);
FORCEADD OFFPAGE..2
(-1125 2800);
FORCEPROP 2 LAST $XR0 185 
J 0
(-936 2800);
DISPLAY 0.638298 (-936 2800);
PAINT MONO (-936 2800);
FORCEPROP 2 LAST PATH I28
J 0
(-950 2875);
DISPLAY 1.361702 (-950 2875);
PAINT ORANGE (-950 2875);
DISPLAY INVISIBLE (-950 2875);
FORCEPROP 2 LAST CDS_LIB mstr_standard
J 0
(-1125 2800);
PAINT ORANGE (-1125 2800);
DISPLAY INVISIBLE (-1125 2800);
FORCEPROP 1 LAST OFFPAGE TRUE
J 0
(-800 2675);
PAINT GREEN (-800 2675);
DISPLAY INVISIBLE (-800 2675);
FORCEPROP 1 LAST COMMENT_BODY TRUE
J 0
(-1170 2705);
DISPLAY 1.170213 (-1170 2705);
PAINT PEACH (-1170 2705);
DISPLAY INVISIBLE (-1170 2705);
FORCEADD OFFPAGE..2
(-1125 2850);
FORCEPROP 2 LAST $XR0 185 
J 0
(-936 2850);
DISPLAY 0.638298 (-936 2850);
PAINT MONO (-936 2850);
FORCEPROP 2 LAST PATH I29
J 0
(-950 2925);
DISPLAY 1.361702 (-950 2925);
PAINT ORANGE (-950 2925);
DISPLAY INVISIBLE (-950 2925);
FORCEPROP 2 LAST CDS_LIB mstr_standard
J 0
(-1125 2850);
PAINT ORANGE (-1125 2850);
DISPLAY INVISIBLE (-1125 2850);
FORCEPROP 1 LAST OFFPAGE TRUE
J 0
(-800 2725);
PAINT GREEN (-800 2725);
DISPLAY INVISIBLE (-800 2725);
FORCEPROP 1 LAST COMMENT_BODY TRUE
J 0
(-1170 2755);
DISPLAY 1.170213 (-1170 2755);
PAINT PEACH (-1170 2755);
DISPLAY INVISIBLE (-1170 2755);
FORCEADD OFFPAGE..2
(-1125 2900);
FORCEPROP 2 LAST $XR0 172 
J 0
(-936 2900);
DISPLAY 0.638298 (-936 2900);
PAINT MONO (-936 2900);
FORCEPROP 2 LAST PATH I30
J 0
(-950 2975);
DISPLAY 1.361702 (-950 2975);
PAINT ORANGE (-950 2975);
DISPLAY INVISIBLE (-950 2975);
FORCEPROP 2 LAST CDS_LIB mstr_standard
J 0
(-1125 2900);
PAINT ORANGE (-1125 2900);
DISPLAY INVISIBLE (-1125 2900);
FORCEPROP 1 LAST OFFPAGE TRUE
J 0
(-800 2775);
PAINT GREEN (-800 2775);
DISPLAY INVISIBLE (-800 2775);
FORCEPROP 1 LAST COMMENT_BODY TRUE
J 0
(-1170 2805);
DISPLAY 1.170213 (-1170 2805);
PAINT PEACH (-1170 2805);
DISPLAY INVISIBLE (-1170 2805);
FORCEADD OFFPAGE..2
(-450 2650);
FORCEPROP 2 LAST $XR0 145 
J 0
(-261 2650);
DISPLAY 0.638298 (-261 2650);
PAINT MONO (-261 2650);
FORCEPROP 2 LAST PATH I31
J 0
(-275 2725);
DISPLAY 1.361702 (-275 2725);
PAINT ORANGE (-275 2725);
DISPLAY INVISIBLE (-275 2725);
FORCEPROP 2 LAST CDS_LIB mstr_standard
J 0
(-450 2650);
PAINT ORANGE (-450 2650);
DISPLAY INVISIBLE (-450 2650);
FORCEPROP 1 LAST OFFPAGE TRUE
J 0
(-125 2525);
PAINT GREEN (-125 2525);
DISPLAY INVISIBLE (-125 2525);
FORCEPROP 1 LAST COMMENT_BODY TRUE
J 0
(-495 2555);
DISPLAY 1.170213 (-495 2555);
PAINT PEACH (-495 2555);
DISPLAY INVISIBLE (-495 2555);
FORCEADD OFFPAGE..2
(-450 2600);
FORCEPROP 2 LAST $XR0 145 
J 0
(-261 2600);
DISPLAY 0.638298 (-261 2600);
PAINT MONO (-261 2600);
FORCEPROP 2 LAST PATH I32
J 0
(-275 2675);
DISPLAY 1.361702 (-275 2675);
PAINT ORANGE (-275 2675);
DISPLAY INVISIBLE (-275 2675);
FORCEPROP 2 LAST CDS_LIB mstr_standard
J 0
(-450 2600);
PAINT ORANGE (-450 2600);
DISPLAY INVISIBLE (-450 2600);
FORCEPROP 1 LAST OFFPAGE TRUE
J 0
(-125 2475);
PAINT GREEN (-125 2475);
DISPLAY INVISIBLE (-125 2475);
FORCEPROP 1 LAST COMMENT_BODY TRUE
J 0
(-495 2505);
DISPLAY 1.170213 (-495 2505);
PAINT PEACH (-495 2505);
DISPLAY INVISIBLE (-495 2505);
FORCEADD OFFPAGE..1
(-7200 2950);
FORCEPROP 2 LAST $XR0 172 
J 0
(-7452 2950);
DISPLAY 0.638298 (-7452 2950);
PAINT MONO (-7452 2950);
FORCEPROP 2 LAST PATH I97
J 0
(-7150 3025);
DISPLAY 1.361702 (-7150 3025);
PAINT ORANGE (-7150 3025);
DISPLAY INVISIBLE (-7150 3025);
FORCEPROP 2 LAST CDS_LIB mstr_standard
J 0
(-7200 2950);
PAINT ORANGE (-7200 2950);
DISPLAY INVISIBLE (-7200 2950);
FORCEPROP 1 LAST OFFPAGE TRUE
J 0
(-6875 2825);
PAINT GREEN (-6875 2825);
DISPLAY INVISIBLE (-6875 2825);
FORCEPROP 1 LAST COMMENT_BODY TRUE
J 0
(-7075 2850);
DISPLAY 1.170213 (-7075 2850);
PAINT PEACH (-7075 2850);
DISPLAY INVISIBLE (-7075 2850);
FORCEADD DNS..2
(-2120 1395);
PAINT RED (-2120 1395);
FORCEPROP 2 LAST CDS_LIB mstr_misc
J 0
(-2120 1395);
PAINT ORANGE (-2120 1395);
DISPLAY INVISIBLE (-2120 1395);
FORCEPROP 1 LAST COMMENT_BODY TRUE
R 1
J 0
(-2045 1170);
DISPLAY 0.872340 (-2045 1170);
PAINT GREEN (-2045 1170);
DISPLAY INVISIBLE (-2045 1170);
FORCEADD INTEL_CORP_BPAGE..1
(0 0);
FORCEPROP 1 LAST CDS_CON_LAST_MODIFIED Fri Jun 16 17:48:46 2017
J 0
(-1425 325);
DISPLAY 1.340426 (-1425 325);
PAINT ORANGE (-1425 325);
DISPLAY INVISIBLE (-1425 325);
FORCEPROP 1 LAST CUSTOM_TXT_CDS <CURRENT_DESIGN_SHEET> OF <TOTAL_DESIGN_SHEETS>
J 0
(-500 25);
PAINT ORANGE (-500 25);
FORCEPROP 1 LAST CUSTOM_TXT_CDS <CON_LAST_MODIFIED>
J 0
(-4000 100);
PAINT ORANGE (-4000 100);
FORCEPROP 2 LAST CUSTOM_TXT_CDS <XR_PAGE_TITLE>
J 0
(-7890 5250);
DISPLAY 0.638298 (-7890 5250);
PAINT PINK (-7890 5250);
DISPLAY INVISIBLE (-7890 5250);
FORCEPROP 1 LAST SCH_TITLE LEWISBURG 3/11 IO
J 0
(-7950 50);
DISPLAY 1.212766 (-7950 50);
PAINT YELLOW (-7950 50);
FORCEPROP 2 LAST CDS_LIB mstr_symbols
J 0
(0 0);
PAINT ORANGE (0 0);
DISPLAY INVISIBLE (0 0);
FORCEPROP 2 LAST PAGE_BORDER TRUE
J 0
(-7890 5250);
DISPLAY 0.851064 (-7890 5250);
PAINT PINK (-7890 5250);
DISPLAY INVISIBLE (-7890 5250);
FORCEPROP 1 LAST COMMENT_BODY TRUE
J 0
(12 12);
DISPLAY 0.638298 (12 12);
PAINT PEACH (12 12);
DISPLAY INVISIBLE (12 12);
FORCEPROP 2 LAST CDS_XR_PAGE_TITLE CR-116 : @BASEBOARD_FAB2_LIB.BASEBOARD_FAB2(SCH_1):PAGE116
J 0
(-7890 5250);
DISPLAY 0.638298 (-7890 5250);
PAINT PINK (-7890 5250);
DISPLAY INVISIBLE (-7890 5250);
FORCEADD DNS..2
(-1820 1395);
PAINT RED (-1820 1395);
FORCEPROP 2 LAST CDS_LIB mstr_misc
J 0
(-1820 1395);
PAINT ORANGE (-1820 1395);
DISPLAY INVISIBLE (-1820 1395);
FORCEPROP 1 LAST COMMENT_BODY TRUE
R 1
J 0
(-1745 1170);
DISPLAY 0.872340 (-1745 1170);
PAINT GREEN (-1745 1170);
DISPLAY INVISIBLE (-1745 1170);
FORCEADD CAD_NOTE..1
(-5150 1000);
FORCEPROP 0 LAST L1 PLACE PULL DOWNS NEAR PCH
J 0
(-5300 875);
DISPLAY 1.021277 (-5300 875);
PAINT WHITE (-5300 875);
FORCEPROP 2 LAST CDS_LIB mstr_symbols
J 0
(-5150 1000);
PAINT ORANGE (-5150 1000);
DISPLAY INVISIBLE (-5150 1000);
FORCEPROP 1 LAST COMMENT_BODY TRUE
J 0
(-5125 1100);
DISPLAY 0.978723 (-5125 1100);
PAINT ORANGE (-5125 1100);
DISPLAY INVISIBLE (-5125 1100);
FORCEADD DESIGN_NOTE..1
(-5100 750);
FORCEPROP 0 LAST L2 USED TO AVOID NOISE INTO LBG PINS
J 0
(-5300 550);
DISPLAY 1.021277 (-5300 550);
PAINT ORANGE (-5300 550);
FORCEPROP 0 LAST L1 PCIE ON AST1250 NOT USED. PULL DOWNS
J 0
(-5300 625);
DISPLAY 1.021277 (-5300 625);
PAINT ORANGE (-5300 625);
FORCEPROP 0 LAST L3 IF AST2400 IS USED, UNSTUFF THESE RESISTORS
J 0
(-5300 475);
DISPLAY 1.021277 (-5300 475);
PAINT ORANGE (-5300 475);
FORCEPROP 2 LAST CDS_LIB mstr_symbols
J 0
(-5100 750);
PAINT ORANGE (-5100 750);
DISPLAY INVISIBLE (-5100 750);
FORCEPROP 1 LAST COMMENT_BODY TRUE
J 0
(-5075 850);
DISPLAY 0.978723 (-5075 850);
PAINT ORANGE (-5075 850);
DISPLAY INVISIBLE (-5075 850);
FORCEADD CAD_NOTE..1
(-950 2450);
FORCEPROP 0 LAST L2 CAPS CLOSE TO PCH
J 0
(-1100 2275);
DISPLAY 0.808511 (-1100 2275);
PAINT ORANGE (-1100 2275);
FORCEPROP 0 LAST L1 PLACE BMC PCIE TX
J 0
(-1100 2325);
DISPLAY 0.808511 (-1100 2325);
PAINT ORANGE (-1100 2325);
FORCEPROP 2 LAST CDS_LIB mstr_symbols
J 0
(-950 2450);
PAINT ORANGE (-950 2450);
DISPLAY INVISIBLE (-950 2450);
FORCEPROP 1 LAST COMMENT_BODY TRUE
J 0
(-925 2550);
DISPLAY 0.978723 (-925 2550);
PAINT ORANGE (-925 2550);
DISPLAY INVISIBLE (-925 2550);
FORCEADD CAD_NOTE..1
(-7375 1525);
FORCEPROP 0 LAST L1 PLACE RCOMP RESISTORS WITHIN 2 INCHES OF PCH
J 0
(-7525 1400);
DISPLAY 1.021277 (-7525 1400);
PAINT WHITE (-7525 1400);
FORCEPROP 2 LAST CDS_LIB mstr_symbols
J 0
(-7375 1525);
PAINT ORANGE (-7375 1525);
DISPLAY INVISIBLE (-7375 1525);
FORCEPROP 1 LAST COMMENT_BODY TRUE
J 0
(-7350 1625);
DISPLAY 0.978723 (-7350 1625);
PAINT ORANGE (-7350 1625);
DISPLAY INVISIBLE (-7350 1625);
WIRE 16 -1 (-1925 1150)(-1925 1050);
WIRE 16 -1 (-1925 1150)(-2125 1150);
WIRE 16 -1 (-1825 1150)(-1925 1150);
WIRE 16 -1 (-1825 1300)(-1825 1150);
WIRE 16 -1 (-2125 1150)(-2125 1300);
WIRE 16 -1 (-6250 525)(-6250 650);
WIRE 16 -1 (-5900 525)(-5900 650);
WIRE 17 -1 (-1975 4225)(-975 4225);
FORCEPROP 2 LAST SIG_NAME SATA6G_PCH_PCIE_UP_SATA_TXP<7:0>
J 0
(-1785 4235);
DISPLAY 0.617021 (-1785 4235);
PAINT ORANGE (-1785 4235);
WIRE 17 -1 (-1975 4225)(-1975 4175);
WIRE 17 -1 (-1975 4075)(-1975 4175);
WIRE 17 -1 (-1975 3975)(-1975 4075);
WIRE 17 -1 (-1975 3575)(-1975 3475);
WIRE 17 -1 (-1975 3875)(-1975 3975);
WIRE 17 -1 (-1975 3775)(-1975 3875);
WIRE 17 -1 (-1975 3675)(-1975 3575);
WIRE 17 -1 (-1975 3675)(-1975 3775);
WIRE 17 -1 (-1825 4175)(-975 4175);
FORCEPROP 2 LAST SIG_NAME SATA6G_PCH_PCIE_UP_SATA_TXN<7:0>
J 0
(-1785 4185);
DISPLAY 0.617021 (-1785 4185);
PAINT ORANGE (-1785 4185);
WIRE 17 -1 (-1825 4175)(-1825 4125);
WIRE 17 -1 (-1825 4125)(-1825 4025);
WIRE 17 -1 (-1825 3425)(-1825 3525);
WIRE 17 -1 (-1825 3525)(-1825 3625);
WIRE 17 -1 (-1825 4025)(-1825 3925);
WIRE 17 -1 (-1825 3825)(-1825 3925);
WIRE 17 -1 (-1825 3625)(-1825 3725);
WIRE 17 -1 (-1825 3725)(-1825 3825);
WIRE 17 -1 (-6450 3575)(-6450 3475);
WIRE 17 -1 (-6450 3675)(-6450 3575);
WIRE 17 -1 (-6450 3775)(-6450 3675);
WIRE 17 -1 (-6450 3875)(-6450 3775);
WIRE 17 -1 (-6450 3975)(-6450 3875);
WIRE 17 -1 (-6450 4075)(-6450 3975);
WIRE 17 -1 (-6450 4175)(-6450 4075);
WIRE 17 -1 (-7400 4250)(-6450 4250);
FORCEPROP 2 LAST SIG_NAME SATA6G_PCH_PCIE_UP_SATA_RXP<7:0>
J 0
(-7360 4260);
DISPLAY 0.617021 (-7360 4260);
PAINT ORANGE (-7360 4260);
WIRE 17 -1 (-6450 4250)(-6450 4175);
WIRE 17 -1 (-6300 3525)(-6300 3425);
WIRE 17 -1 (-6300 3625)(-6300 3525);
WIRE 17 -1 (-6300 3725)(-6300 3625);
WIRE 17 -1 (-6300 3825)(-6300 3725);
WIRE 17 -1 (-6300 3925)(-6300 3825);
WIRE 17 -1 (-6300 4025)(-6300 3925);
WIRE 17 -1 (-6300 4125)(-6300 4025);
WIRE 17 -1 (-7400 4300)(-6300 4300);
FORCEPROP 2 LAST SIG_NAME SATA6G_PCH_PCIE_UP_SATA_RXN<7:0>
J 0
(-7360 4310);
DISPLAY 0.617021 (-7360 4310);
PAINT ORANGE (-7360 4310);
WIRE 17 -1 (-6300 4300)(-6300 4125);
WIRE 3 2175 (-1875 2675)(-1175 2675);
WIRE 3 2175 (-1175 2575)(-1175 2675);
WIRE 3 2175 (-1875 2575)(-1875 2675);
WIRE 3 2175 (-1875 2575)(-1175 2575);
WIRE 16 -1 (-2425 1750)(-1825 1750);
FORCEPROP 2 LAST SIG_NAME A_EXTCLKP
J 0
(-2285 1760);
DISPLAY 0.617021 (-2285 1760);
PAINT ORANGE (-2285 1760);
FORCEPROP 2 LASTPROP $XRERR UNIQUE?
J 0
(-2525 1760);
DISPLAY 0.638298 (-2525 1760);
PAINT MONO (-2525 1760);
DISPLAY INVISIBLE (-2525 1760);
WIRE 16 -1 (-1825 1500)(-1825 1750);
WIRE 16 -1 (-500 2600)(-1225 2600);
FORCEPROP 2 LAST SIG_NAME P2E_SSB_BMC_TX_C_DN
J 0
(-960 2610);
DISPLAY 0.617021 (-960 2610);
PAINT ORANGE (-960 2610);
WIRE 16 -1 (-2425 2900)(-1175 2900);
FORCEPROP 0 LAST SIG_NAME SATA6G_S1_TX_DN
J 2
(-1188 2910);
DISPLAY 0.617021 (-1188 2910);
PAINT ORANGE (-1188 2910);
WIRE 16 -1 (-2425 2950)(-1175 2950);
FORCEPROP 0 LAST SIG_NAME SATA6G_S1_TX_DP
J 2
(-1188 2960);
DISPLAY 0.617021 (-1188 2960);
PAINT ORANGE (-1188 2960);
WIRE 16 -1 (-2425 2600)(-1425 2600);
FORCEPROP 2 LAST SIG_NAME P2E_SSB_BMC_TX_DN
J 0
(-2310 2610);
DISPLAY 0.617021 (-2310 2610);
PAINT ORANGE (-2310 2610);
FORCEPROP 2 LASTPROP $XRERR UNIQUE?
J 0
(-2550 2610);
DISPLAY 0.638298 (-2550 2610);
PAINT MONO (-2550 2610);
DISPLAY INVISIBLE (-2550 2610);
WIRE 16 -1 (-2425 2500)(-1800 2500);
FORCEPROP 2 LAST SIG_NAME P3E_PCH_M2_TX_DP<3>
J 0
(-2260 2510);
DISPLAY 0.617021 (-2260 2510);
PAINT ORANGE (-2260 2510);
WIRE 16 -1 (-6350 4050)(-5625 4050);
WIRE 16 -1 (-6350 3550)(-5625 3550);
WIRE 16 -1 (-6200 3500)(-5625 3500);
WIRE 16 -1 (-6350 3850)(-5625 3850);
WIRE 16 -1 (-6350 3650)(-5625 3650);
WIRE 16 -1 (-6200 3600)(-5625 3600);
WIRE 16 -1 (-6350 3450)(-5625 3450);
WIRE 16 -1 (-6200 3400)(-5625 3400);
WIRE 3 682 (-5800 3000)(-5750 3000);
WIRE 3 682 (-5800 3300)(-5800 3000);
WIRE 3 682 (-5850 3300)(-5800 3300);
WIRE 3 682 (-5800 3350)(-5800 3300);
WIRE 3 682 (-5750 3350)(-5800 3350);
WIRE 16 -1 (-7150 2950)(-5625 2950);
FORCEPROP 0 LAST SIG_NAME SATA6G_S1_RX_DP
J 0
(-7138 2960);
DISPLAY 0.617021 (-7138 2960);
PAINT ORANGE (-7138 2960);
WIRE 16 -1 (-7150 2900)(-5625 2900);
FORCEPROP 0 LAST SIG_NAME SATA6G_S1_RX_DN
J 0
(-7138 2910);
DISPLAY 0.617021 (-7138 2910);
PAINT ORANGE (-7138 2910);
WIRE 16 -1 (-6200 3700)(-5625 3700);
WIRE 16 -1 (-6350 3750)(-5625 3750);
WIRE 16 -1 (-6200 3800)(-5625 3800);
WIRE 16 -1 (-6200 3900)(-5625 3900);
WIRE 16 -1 (-6350 3950)(-5625 3950);
WIRE 16 -1 (-6200 4000)(-5625 4000);
WIRE 3 682 (-2250 3000)(-2300 3000);
WIRE 3 682 (-2250 3300)(-2250 3000);
WIRE 3 682 (-2250 3300)(-2200 3300);
WIRE 3 682 (-2250 3350)(-2250 3300);
WIRE 3 682 (-2300 3350)(-2250 3350);
WIRE 16 -1 (-2425 3600)(-1925 3600);
WIRE 16 -1 (-2425 3650)(-2075 3650);
WIRE 16 -1 (-2425 3550)(-2075 3550);
WIRE 16 -1 (-2425 3500)(-1925 3500);
WIRE 16 -1 (-2425 3400)(-1925 3400);
WIRE 16 -1 (-2425 3450)(-2075 3450);
WIRE 16 -1 (-2425 3700)(-1925 3700);
WIRE 16 -1 (-2425 2800)(-1175 2800);
FORCEPROP 0 LAST SIG_NAME SATA6G_S0_TX_DN
J 2
(-1188 2810);
DISPLAY 0.617021 (-1188 2810);
PAINT ORANGE (-1188 2810);
WIRE 16 -1 (-2425 2750)(-1175 2750);
FORCEPROP 0 LAST SIG_NAME PE_PCH_SPRV_TX_DP
J 2
(-1188 2760);
DISPLAY 0.617021 (-1188 2760);
PAINT ORANGE (-1188 2760);
WIRE 16 -1 (-1175 2700)(-2425 2700);
FORCEPROP 0 LAST SIG_NAME PE_PCH_SPRV_TX_DN
J 2
(-1188 2710);
DISPLAY 0.617021 (-1188 2710);
PAINT ORANGE (-1188 2710);
WIRE 16 -1 (-7150 2850)(-5625 2850);
FORCEPROP 0 LAST SIG_NAME SATA6G_S0_RX_DP
J 0
(-7138 2860);
DISPLAY 0.617021 (-7138 2860);
PAINT ORANGE (-7138 2860);
WIRE 16 -1 (-7150 2800)(-5625 2800);
FORCEPROP 0 LAST SIG_NAME SATA6G_S0_RX_DN
J 0
(-7138 2810);
DISPLAY 0.617021 (-7138 2810);
PAINT ORANGE (-7138 2810);
WIRE 16 -1 (-7150 2750)(-5625 2750);
FORCEPROP 0 LAST SIG_NAME PE_PCH_SPRV_RX_C_DP
J 0
(-7138 2760);
DISPLAY 0.617021 (-7138 2760);
PAINT ORANGE (-7138 2760);
WIRE 16 -1 (-5625 2700)(-7150 2700);
FORCEPROP 0 LAST SIG_NAME PE_PCH_SPRV_RX_C_DN
J 0
(-7138 2710);
DISPLAY 0.617021 (-7138 2710);
PAINT ORANGE (-7138 2710);
WIRE 16 -1 (-7150 2650)(-5625 2650);
FORCEPROP 0 LAST SIG_NAME P2E_SSB_BMC_RX_C_DP
J 0
(-7138 2660);
DISPLAY 0.617021 (-7138 2660);
PAINT ORANGE (-7138 2660);
WIRE 16 -1 (-7150 2600)(-5625 2600);
FORCEPROP 0 LAST SIG_NAME P2E_SSB_BMC_RX_C_DN
J 0
(-7138 2610);
DISPLAY 0.617021 (-7138 2610);
PAINT ORANGE (-7138 2610);
WIRE 3 682 (-6350 1100)(-6350 400);
WIRE 3 682 (-5500 1100)(-6350 1100);
WIRE 3 682 (-6350 400)(-5500 400);
WIRE 3 682 (-5500 400)(-5500 1100);
WIRE 16 -1 (-7550 1700)(-7550 2050);
WIRE 16 -1 (-7550 1700)(-5625 1700);
FORCEPROP 0 LAST SIG_NAME A_PCIE_RCOMP_N
J 0
(-6978 1701);
DISPLAY 0.617021 (-6978 1701);
PAINT ORANGE (-6978 1701);
FORCEPROP 2 LASTPROP $XRERR UNIQUE?
J 0
(-7218 1701);
DISPLAY 0.638298 (-7218 1701);
PAINT MONO (-7218 1701);
DISPLAY INVISIBLE (-7218 1701);
WIRE 16 -1 (-7125 1800)(-7125 2050);
WIRE 16 -1 (-7125 1800)(-5625 1800);
FORCEPROP 0 LAST SIG_NAME A_PCIEUP_RCOMP_N
J 0
(-6978 1801);
DISPLAY 0.617021 (-6978 1801);
PAINT ORANGE (-6978 1801);
FORCEPROP 2 LASTPROP $XRERR UNIQUE?
J 0
(-7218 1801);
DISPLAY 0.638298 (-7218 1801);
PAINT MONO (-7218 1801);
DISPLAY INVISIBLE (-7218 1801);
WIRE 16 -1 (-7125 2250)(-7125 2300);
WIRE 16 -1 (-7025 2300)(-7125 2300);
WIRE 16 -1 (-7025 2300)(-7025 1850);
WIRE 16 -1 (-7025 1850)(-5625 1850);
FORCEPROP 0 LAST SIG_NAME A_PCIEUP_RCOMP_P
J 0
(-6978 1851);
DISPLAY 0.617021 (-6978 1851);
PAINT ORANGE (-6978 1851);
FORCEPROP 2 LASTPROP $XRERR UNIQUE?
J 0
(-7218 1851);
DISPLAY 0.638298 (-7218 1851);
PAINT MONO (-7218 1851);
DISPLAY INVISIBLE (-7218 1851);
WIRE 16 -1 (-6850 2000)(-5625 2000);
FORCEPROP 2 LAST SIG_NAME TP_PCH_RSVD47
J 0
(-6860 2010);
DISPLAY 0.617021 (-6860 2010);
PAINT ORANGE (-6860 2010);
FORCEPROP 2 LASTPROP $XRERR UNIQUE?
J 0
(-7090 2000);
DISPLAY 0.638298 (-7090 2000);
PAINT MONO (-7090 2000);
DISPLAY INVISIBLE (-7090 2000);
WIRE 16 -1 (-6850 2050)(-5625 2050);
FORCEPROP 2 LAST SIG_NAME TP_PCH_RSVD48
J 0
(-6860 2060);
DISPLAY 0.617021 (-6860 2060);
PAINT ORANGE (-6860 2060);
FORCEPROP 2 LASTPROP $XRERR UNIQUE?
J 0
(-7090 2050);
DISPLAY 0.638298 (-7090 2050);
PAINT MONO (-7090 2050);
DISPLAY INVISIBLE (-7090 2050);
WIRE 16 -1 (-6450 2150)(-5625 2150);
FORCEPROP 2 LAST SIG_NAME P3E_PCH_RX_0_DN
J 0
(-6450 2160);
DISPLAY 0.617021 (-6450 2160);
PAINT ORANGE (-6450 2160);
WIRE 16 -1 (-7550 2250)(-7550 2300);
WIRE 16 -1 (-7450 2300)(-7550 2300);
WIRE 16 -1 (-7450 2300)(-7450 1750);
WIRE 16 -1 (-7450 1750)(-5625 1750);
FORCEPROP 0 LAST SIG_NAME A_PCIE_RCOMP_P
J 0
(-6978 1751);
DISPLAY 0.617021 (-6978 1751);
PAINT ORANGE (-6978 1751);
FORCEPROP 2 LASTPROP $XRERR UNIQUE?
J 0
(-7218 1751);
DISPLAY 0.638298 (-7218 1751);
PAINT MONO (-7218 1751);
DISPLAY INVISIBLE (-7218 1751);
WIRE 16 -1 (-5900 1050)(-7150 1050);
FORCEPROP 2 LAST SIG_NAME P2E_SSB_BMC_RX_C_DP
J 0
(-7110 1060);
DISPLAY 0.617021 (-7110 1060);
PAINT ORANGE (-7110 1060);
WIRE 16 -1 (-5900 850)(-5900 1050);
WIRE 16 -1 (-6250 950)(-7150 950);
FORCEPROP 2 LAST SIG_NAME P2E_SSB_BMC_RX_C_DN
J 0
(-7110 960);
DISPLAY 0.617021 (-7110 960);
PAINT ORANGE (-7110 960);
WIRE 16 -1 (-6250 850)(-6250 950);
WIRE 16 -1 (-500 2650)(-1625 2650);
FORCEPROP 2 LAST SIG_NAME P2E_SSB_BMC_TX_C_DP
J 0
(-960 2660);
DISPLAY 0.617021 (-960 2660);
PAINT ORANGE (-960 2660);
WIRE 16 -1 (-2425 1900)(-1950 1900);
FORCEPROP 2 LAST SIG_NAME TP_PCH_RSVD52
J 0
(-2260 1910);
DISPLAY 0.617021 (-2260 1910);
PAINT ORANGE (-2260 1910);
FORCEPROP 2 LASTPROP $XRERR UNIQUE?
J 0
(-1920 1900);
DISPLAY 0.638298 (-1920 1900);
PAINT MONO (-1920 1900);
DISPLAY INVISIBLE (-1920 1900);
WIRE 16 -1 (-6200 4100)(-5625 4100);
WIRE 16 -1 (-2425 2350)(-1800 2350);
FORCEPROP 2 LAST SIG_NAME P3E_PCH_M2_TX_DN<2>
J 0
(-2260 2360);
DISPLAY 0.617021 (-2260 2360);
PAINT ORANGE (-2260 2360);
WIRE 16 -1 (-6450 2400)(-5625 2400);
WIRE 16 -1 (-6450 2350)(-5625 2350);
FORCEPROP 2 LAST SIG_NAME P3E_PCH_M2_RX_DN<2>
J 0
(-6450 2360);
DISPLAY 0.617021 (-6450 2360);
PAINT ORANGE (-6450 2360);
WIRE 16 -1 (-2425 2300)(-1800 2300);
FORCEPROP 2 LAST SIG_NAME P3E_PCH_M2_TX_DP<1>
J 0
(-2260 2310);
DISPLAY 0.617021 (-2260 2310);
PAINT ORANGE (-2260 2310);
WIRE 16 -1 (-1800 2250)(-2425 2250);
FORCEPROP 2 LAST SIG_NAME P3E_PCH_M2_TX_DN<1>
J 0
(-2260 2260);
DISPLAY 0.617021 (-2260 2260);
PAINT ORANGE (-2260 2260);
WIRE 16 -1 (-2425 2200)(-1800 2200);
FORCEPROP 2 LAST SIG_NAME P3E_PCH_TX_0_DP
J 0
(-2260 2210);
DISPLAY 0.617021 (-2260 2210);
PAINT ORANGE (-2260 2210);
WIRE 16 -1 (-6450 2200)(-5625 2200);
FORCEPROP 2 LAST SIG_NAME P3E_PCH_RX_0_DP
J 0
(-6450 2210);
DISPLAY 0.617021 (-6450 2210);
PAINT ORANGE (-6450 2210);
WIRE 16 -1 (-2425 2450)(-1800 2450);
FORCEPROP 2 LAST SIG_NAME P3E_PCH_M2_TX_DN<3>
J 0
(-2260 2460);
DISPLAY 0.617021 (-2260 2460);
PAINT ORANGE (-2260 2460);
WIRE 16 -1 (-6450 2450)(-5625 2450);
WIRE 16 -1 (-2425 2000)(-1950 2000);
FORCEPROP 2 LAST SIG_NAME TP_PCH_RSVD49
J 0
(-2260 2010);
DISPLAY 0.617021 (-2260 2010);
PAINT ORANGE (-2260 2010);
FORCEPROP 2 LASTPROP $XRERR UNIQUE?
J 0
(-1920 2000);
DISPLAY 0.638298 (-1920 2000);
PAINT MONO (-1920 2000);
DISPLAY INVISIBLE (-1920 2000);
WIRE 16 -1 (-2425 4150)(-2075 4150);
WIRE 16 -1 (-2425 4100)(-1925 4100);
WIRE 16 -1 (-6350 4150)(-5625 4150);
WIRE 16 -1 (-2425 4050)(-2075 4050);
WIRE 16 -1 (-2425 4000)(-1925 4000);
WIRE 16 -1 (-2425 3950)(-2075 3950);
WIRE 16 -1 (-2425 3900)(-1925 3900);
WIRE 16 -1 (-2425 3850)(-2075 3850);
WIRE 16 -1 (-2425 3800)(-1925 3800);
WIRE 16 -1 (-2425 3750)(-2075 3750);
WIRE 16 -1 (-5625 2250)(-6450 2250);
FORCEPROP 2 LAST SIG_NAME P3E_PCH_M2_RX_DN<1>
J 0
(-6450 2260);
DISPLAY 0.617021 (-6450 2260);
PAINT ORANGE (-6450 2260);
WIRE 16 -1 (-6450 2300)(-5625 2300);
FORCEPROP 2 LAST SIG_NAME P3E_PCH_M2_RX_DP<1>
J 0
(-6450 2310);
DISPLAY 0.617021 (-6450 2310);
PAINT ORANGE (-6450 2310);
WIRE 16 -1 (-6450 2500)(-5625 2500);
WIRE 16 -1 (-2425 2850)(-1175 2850);
FORCEPROP 0 LAST SIG_NAME SATA6G_S0_TX_DP
J 2
(-1188 2860);
DISPLAY 0.617021 (-1188 2860);
PAINT ORANGE (-1188 2860);
WIRE 16 -1 (-2425 2650)(-1825 2650);
FORCEPROP 2 LAST SIG_NAME P2E_SSB_BMC_TX_DP
J 0
(-2310 2660);
DISPLAY 0.617021 (-2310 2660);
PAINT ORANGE (-2310 2660);
FORCEPROP 2 LASTPROP $XRERR UNIQUE?
J 0
(-2550 2660);
DISPLAY 0.638298 (-2550 2660);
PAINT MONO (-2550 2660);
DISPLAY INVISIBLE (-2550 2660);
WIRE 16 -1 (-2425 2400)(-1800 2400);
FORCEPROP 2 LAST SIG_NAME P3E_PCH_M2_TX_DP<2>
J 0
(-2260 2410);
DISPLAY 0.617021 (-2260 2410);
PAINT ORANGE (-2260 2410);
WIRE 16 -1 (-2425 2050)(-1950 2050);
FORCEPROP 2 LAST SIG_NAME TP_PCH_RSVD50
J 0
(-2260 2060);
DISPLAY 0.617021 (-2260 2060);
PAINT ORANGE (-2260 2060);
FORCEPROP 2 LASTPROP $XRERR UNIQUE?
J 0
(-1920 2050);
DISPLAY 0.638298 (-1920 2050);
PAINT MONO (-1920 2050);
DISPLAY INVISIBLE (-1920 2050);
WIRE 16 -1 (-2425 1850)(-1950 1850);
FORCEPROP 2 LAST SIG_NAME TP_PCH_RSVD51
J 0
(-2260 1860);
DISPLAY 0.617021 (-2260 1860);
PAINT ORANGE (-2260 1860);
FORCEPROP 2 LASTPROP $XRERR UNIQUE?
J 0
(-1920 1850);
DISPLAY 0.638298 (-1920 1850);
PAINT MONO (-1920 1850);
DISPLAY INVISIBLE (-1920 1850);
WIRE 16 -1 (-2125 1700)(-2125 1500);
WIRE 16 -1 (-2425 1700)(-2125 1700);
FORCEPROP 2 LAST SIG_NAME A_EXTCLKN
J 0
(-2285 1710);
DISPLAY 0.617021 (-2285 1710);
PAINT ORANGE (-2285 1710);
FORCEPROP 2 LASTPROP $XRERR UNIQUE?
J 0
(-2525 1710);
DISPLAY 0.638298 (-2525 1710);
PAINT MONO (-2525 1710);
DISPLAY INVISIBLE (-2525 1710);
WIRE 16 -1 (-2425 2150)(-1800 2150);
FORCEPROP 2 LAST SIG_NAME P3E_PCH_TX_0_DN
J 0
(-2260 2160);
DISPLAY 0.617021 (-2260 2160);
PAINT ORANGE (-2260 2160);
DOT 1 (-5800 3300);
DOT 1 (-2250 3300);
DOT 1 (-1925 1150);
FORCENOTE
TP FAB3 DELETE NET 0920
(-6700 3300) 0;
DISPLAY LEFT (-6700 3300);
DISPLAY 1.021277 (-6700 3300);
PAINT RED (-6700 3300);
FORCENOTE
TP FAB3 DELETE NET 0920
(-2175 3300) 0;
DISPLAY LEFT (-2175 3300);
DISPLAY 1.021277 (-2175 3300);
PAINT RED (-2175 3300);
FORCENOTE
MINI-SAS X8 VERTICAL
(-1075 3950) 0;
DISPLAY LEFT (-1075 3950);
DISPLAY 1.021277 (-1075 3950);
PAINT PURPLE (-1075 3950);
FORCENOTE
MINI-SAS X8 VERTICAL
(-7650 4025) 0;
DISPLAY LEFT (-7650 4025);
DISPLAY 1.021277 (-7650 4025);
PAINT PURPLE (-7650 4025);
FORCENOTE
M.2 PCIE
(-7200 2400) 0;
DISPLAY LEFT (-7200 2400);
DISPLAY 1.021277 (-7200 2400);
PAINT PURPLE (-7200 2400);
FORCENOTE
M.2 SATA
(-7875 2825) 0;
DISPLAY LEFT (-7875 2825);
DISPLAY 1.021277 (-7875 2825);
PAINT PURPLE (-7875 2825);
FORCENOTE
SATA CONN
(-7950 2925) 0;
DISPLAY LEFT (-7950 2925);
DISPLAY 1.021277 (-7950 2925);
PAINT PURPLE (-7950 2925);
FORCENOTE
BMC
(-7725 2600) 0;
DISPLAY LEFT (-7725 2600);
DISPLAY 1.021277 (-7725 2600);
PAINT PURPLE (-7725 2600);
FORCENOTE
SPRV
(-7750 2725) 0;
DISPLAY LEFT (-7750 2725);
DISPLAY 1.021277 (-7750 2725);
PAINT PURPLE (-7750 2725);
FORCENOTE
ROOM=SB
(-7900 250) 0;
DISPLAY LEFT (-7900 250);
DISPLAY 1.021277 (-7900 250);
PAINT PURPLE (-7900 250);
FORCENOTE
M.2 SATA
(-625 2825) 0;
DISPLAY LEFT (-625 2825);
DISPLAY 1.021277 (-625 2825);
PAINT PURPLE (-625 2825);
FORCENOTE
SATA CONN
(-625 2900) 0;
DISPLAY LEFT (-625 2900);
DISPLAY 1.021277 (-625 2900);
PAINT PURPLE (-625 2900);
FORCENOTE
BMC
(-475 2475) 0;
DISPLAY LEFT (-475 2475);
DISPLAY 1.021277 (-475 2475);
PAINT PURPLE (-475 2475);
FORCENOTE
SPRV
(-625 2750) 0;
DISPLAY LEFT (-625 2750);
DISPLAY 1.021277 (-625 2750);
PAINT PURPLE (-625 2750);
FORCENOTE
TP FAB1 POP WHEN AST2500 0106
(-875 2525) 0;
DISPLAY LEFT (-875 2525);
DISPLAY 0.638298 (-875 2525);
PAINT RED (-875 2525);
FORCENOTE
TP FAB3 NOPOP RES 0913
(-6375 350) 0;
DISPLAY LEFT (-6375 350);
DISPLAY 0.638298 (-6375 350);
PAINT RED (-6375 350);
FORCENOTE
M.2 PCIE
(-1325 2200) 0;
DISPLAY LEFT (-1325 2200);
DISPLAY 1.021277 (-1325 2200);
PAINT PURPLE (-1325 2200);
QUIT
